FILE_TYPE = MACRO_DRAWING;
SET COLOR_WIRE YELLOW;
SET COLOR_PROP ORANGE;
SET COLOR_DOT WHITE;
SET COLOR_ARC YELLOW;
SET COLOR_BODY GREEN;
SET COLOR_NOTE PURPLE;
SET PROP_DISPLAY VALUE;
SET PAGE_NUMBER P76;
FORCEADD OFFPAGE..2
R 2
(-3125 5450);
FORCEPROP 2 LAST $XR1 150 
J 0
(-3499 5450);
DISPLAY 0.638298 (-3499 5450);
PAINT MONO (-3499 5450);
FORCEPROP 2 LAST $XR0 77 
J 0
(-3379 5450);
DISPLAY 0.638298 (-3379 5450);
PAINT MONO (-3379 5450);
FORCEPROP 2 LAST CDS_LIB standard
J 2
(-3125 5450);
DISPLAY INVISIBLE (-3125 5450);
FORCEPROP 1 LAST OFFPAGE TRUE
J 2
(-3450 5325);
DISPLAY 0.872340 (-3450 5325);
PAINT GREEN (-3450 5325);
DISPLAY INVISIBLE (-3450 5325);
FORCEPROP 1 LAST COMMENT_BODY TRUE
J 2
(-3080 5355);
DISPLAY 0.872340 (-3080 5355);
PAINT PEACH (-3080 5355);
DISPLAY INVISIBLE (-3080 5355);
FORCEPROP 2 LAST PATH I100
J 0
(-3375 5500);
DISPLAY 1.021277 (-3375 5500);
DISPLAY INVISIBLE (-3375 5500);
FORCEADD OFFPAGE..2
R 2
(-3125 5250);
FORCEPROP 2 LAST $XR1 150 
J 0
(-3499 5250);
DISPLAY 0.638298 (-3499 5250);
PAINT MONO (-3499 5250);
FORCEPROP 2 LAST $XR0 77 
J 0
(-3379 5250);
DISPLAY 0.638298 (-3379 5250);
PAINT MONO (-3379 5250);
FORCEPROP 2 LAST CDS_LIB standard
J 2
(-3125 5250);
DISPLAY INVISIBLE (-3125 5250);
FORCEPROP 1 LAST OFFPAGE TRUE
J 2
(-3450 5125);
DISPLAY 0.872340 (-3450 5125);
PAINT GREEN (-3450 5125);
DISPLAY INVISIBLE (-3450 5125);
FORCEPROP 1 LAST COMMENT_BODY TRUE
J 2
(-3080 5155);
DISPLAY 0.872340 (-3080 5155);
PAINT PEACH (-3080 5155);
DISPLAY INVISIBLE (-3080 5155);
FORCEPROP 2 LAST PATH I101
J 0
(-3375 5300);
DISPLAY 1.021277 (-3375 5300);
DISPLAY INVISIBLE (-3375 5300);
FORCEADD OFFPAGE..2
R 2
(-3125 5200);
FORCEPROP 2 LAST $XR1 150 
J 0
(-3499 5200);
DISPLAY 0.638298 (-3499 5200);
PAINT MONO (-3499 5200);
FORCEPROP 2 LAST $XR0 77 
J 0
(-3379 5200);
DISPLAY 0.638298 (-3379 5200);
PAINT MONO (-3379 5200);
FORCEPROP 2 LAST CDS_LIB standard
J 2
(-3125 5200);
DISPLAY INVISIBLE (-3125 5200);
FORCEPROP 1 LAST OFFPAGE TRUE
J 2
(-3450 5075);
DISPLAY 0.872340 (-3450 5075);
PAINT GREEN (-3450 5075);
DISPLAY INVISIBLE (-3450 5075);
FORCEPROP 1 LAST COMMENT_BODY TRUE
J 2
(-3080 5105);
DISPLAY 0.872340 (-3080 5105);
PAINT PEACH (-3080 5105);
DISPLAY INVISIBLE (-3080 5105);
FORCEPROP 2 LAST PATH I102
J 0
(-3375 5250);
DISPLAY 1.021277 (-3375 5250);
DISPLAY INVISIBLE (-3375 5250);
FORCEADD OFFPAGE..3
R 2
(-3125 5350);
FORCEPROP 2 LAST $XR1 150 
J 0
(-3494 5350);
DISPLAY 0.638298 (-3494 5350);
PAINT MONO (-3494 5350);
FORCEPROP 2 LAST $XR0 77 
J 0
(-3374 5350);
DISPLAY 0.638298 (-3374 5350);
PAINT MONO (-3374 5350);
FORCEPROP 2 LAST CDS_LIB standard
J 0
(-3125 5350);
DISPLAY INVISIBLE (-3125 5350);
FORCEPROP 1 LAST OFFPAGE TRUE
J 2
(-3450 5225);
DISPLAY 0.872340 (-3450 5225);
PAINT GREEN (-3450 5225);
DISPLAY INVISIBLE (-3450 5225);
FORCEPROP 1 LAST COMMENT_BODY TRUE
J 2
(-3075 5250);
DISPLAY 0.872340 (-3075 5250);
PAINT PEACH (-3075 5250);
DISPLAY INVISIBLE (-3075 5250);
FORCEPROP 2 LAST PATH I103
J 0
(-3350 5400);
DISPLAY 1.021277 (-3350 5400);
DISPLAY INVISIBLE (-3350 5400);
FORCEADD OFFPAGE..3
R 2
(-3125 5300);
FORCEPROP 2 LAST $XR1 150 
J 0
(-3494 5300);
DISPLAY 0.638298 (-3494 5300);
PAINT MONO (-3494 5300);
FORCEPROP 2 LAST $XR0 77 
J 0
(-3374 5300);
DISPLAY 0.638298 (-3374 5300);
PAINT MONO (-3374 5300);
FORCEPROP 2 LAST CDS_LIB standard
J 0
(-3125 5300);
DISPLAY INVISIBLE (-3125 5300);
FORCEPROP 1 LAST OFFPAGE TRUE
J 2
(-3450 5175);
DISPLAY 0.872340 (-3450 5175);
PAINT GREEN (-3450 5175);
DISPLAY INVISIBLE (-3450 5175);
FORCEPROP 1 LAST COMMENT_BODY TRUE
J 2
(-3075 5200);
DISPLAY 0.872340 (-3075 5200);
PAINT PEACH (-3075 5200);
DISPLAY INVISIBLE (-3075 5200);
FORCEPROP 2 LAST PATH I104
J 0
(-3350 5350);
DISPLAY 1.021277 (-3350 5350);
DISPLAY INVISIBLE (-3350 5350);
FORCEADD UNIVERSAL_POWER..1
(-8025 6075);
FORCEPROP 3 LASTPIN (-8025 6025) SIG_NAME PVDD18_S5_P0\g
J 0
(-8015 6035);
DISPLAY 0.659574 (-8015 6035);
PAINT MONO (-8015 6035);
DISPLAY INVISIBLE (-8015 6035);
FORCEPROP 1 LAST HDL_POWER PVDD18_S5_P0
J 1
(-8025 6125);
DISPLAY 0.489362 (-8025 6125);
PAINT GREEN (-8025 6125);
FORCEPROP 2 LAST CDS_LIB pure_quanta_power
J 0
(-8025 6075);
DISPLAY INVISIBLE (-8025 6075);
FORCEPROP 1 LAST PATH I105
J 0
(-7975 6100);
DISPLAY 0.872340 (-7975 6100);
PAINT AQUA (-7975 6100);
DISPLAY INVISIBLE (-7975 6100);
FORCEADD Q_RES..2
(-8025 5875);
FORCEPROP 1 LAST LOCATION R811
J 0
(-8000 5750);
DISPLAY 0.489362 (-8000 5750);
PAINT SKYBLUE (-8000 5750);
FORCEPROP 2 LAST $SEC 1
J 0
(-7975 6100);
DISPLAY 0.680851 (-7975 6100);
PAINT MONO (-7975 6100);
DISPLAY INVISIBLE (-7975 6100);
FORCEPROP 2 LAST CDS_SEC 1
J 0
(-7975 6100);
DISPLAY 0.680851 (-7975 6100);
DISPLAY INVISIBLE (-7975 6100);
FORCEPROP 1 LASTPIN (-8025 5975) $PN 1
J 0
(-8020 5937);
DISPLAY 0.489362 (-8020 5937);
PAINT MONO (-8020 5937);
FORCEPROP 1 LASTPIN (-8025 5775) $PN 2
J 0
(-8020 5785);
DISPLAY 0.489362 (-8020 5785);
PAINT MONO (-8020 5785);
FORCEPROP 1 LAST TOLERANCE 1%
J 0
(-7980 5900);
DISPLAY 0.489362 (-7980 5900);
PAINT SKYBLUE (-7980 5900);
FORCEPROP 1 LAST MATERIAL CHIP
J 0
(-7985 5800);
DISPLAY 0.489362 (-7985 5800);
PAINT SKYBLUE (-7985 5800);
FORCEPROP 1 LAST WATTAGE 1/16W
J 0
(-7985 5850);
DISPLAY 0.489362 (-7985 5850);
PAINT SKYBLUE (-7985 5850);
FORCEPROP 1 LAST VALUE 1K
J 0
(-7980 5950);
DISPLAY 0.489362 (-7980 5950);
PAINT SKYBLUE (-7980 5950);
FORCEPROP 2 LAST CDS_LIB pure_quanta
J 0
(-8025 5875);
DISPLAY INVISIBLE (-8025 5875);
FORCEPROP 1 LAST PACK_TYPE 0402LF
J 0
(-7975 5750);
DISPLAY 0.382979 (-7975 5750);
PAINT SKYBLUE (-7975 5750);
DISPLAY INVISIBLE (-7975 5750);
FORCEPROP 1 LAST PATH I106
J 0
(-7975 6050);
DISPLAY 0.978723 (-7975 6050);
PAINT WHITE (-7975 6050);
DISPLAY INVISIBLE (-7975 6050);
FORCEPROP 1 LAST PART_NUMBER CS21002FB06
J 0
(-7985 5750);
DISPLAY 0.489362 (-7985 5750);
PAINT SKYBLUE (-7985 5750);
DISPLAY INVISIBLE (-7985 5750);
FORCEADD Q_RES..2
(-8200 5875);
FORCEPROP 1 LAST LOCATION R659
J 0
(-8175 5750);
DISPLAY 0.489362 (-8175 5750);
PAINT SKYBLUE (-8175 5750);
FORCEPROP 2 LAST $SEC 1
J 0
(-8150 6100);
DISPLAY 0.680851 (-8150 6100);
PAINT MONO (-8150 6100);
DISPLAY INVISIBLE (-8150 6100);
FORCEPROP 2 LAST CDS_SEC 1
J 0
(-8150 6100);
DISPLAY 0.680851 (-8150 6100);
DISPLAY INVISIBLE (-8150 6100);
FORCEPROP 1 LASTPIN (-8200 5975) $PN 1
J 0
(-8195 5937);
DISPLAY 0.489362 (-8195 5937);
PAINT MONO (-8195 5937);
FORCEPROP 1 LASTPIN (-8200 5775) $PN 2
J 0
(-8195 5785);
DISPLAY 0.489362 (-8195 5785);
PAINT MONO (-8195 5785);
FORCEPROP 1 LAST TOLERANCE 1%
J 0
(-8155 5900);
DISPLAY 0.489362 (-8155 5900);
PAINT SKYBLUE (-8155 5900);
FORCEPROP 1 LAST WATTAGE 1/16W
J 0
(-8160 5850);
DISPLAY 0.489362 (-8160 5850);
PAINT SKYBLUE (-8160 5850);
FORCEPROP 1 LAST MATERIAL CHIP
J 0
(-8160 5800);
DISPLAY 0.489362 (-8160 5800);
PAINT SKYBLUE (-8160 5800);
FORCEPROP 1 LAST VALUE 1K
J 0
(-8155 5950);
DISPLAY 0.489362 (-8155 5950);
PAINT SKYBLUE (-8155 5950);
FORCEPROP 2 LAST CDS_LIB pure_quanta
J 0
(-8200 5875);
DISPLAY INVISIBLE (-8200 5875);
FORCEPROP 1 LAST PACK_TYPE 0402LF
J 0
(-8150 5750);
DISPLAY 0.382979 (-8150 5750);
PAINT SKYBLUE (-8150 5750);
DISPLAY INVISIBLE (-8150 5750);
FORCEPROP 1 LAST PATH I107
J 0
(-8150 6050);
DISPLAY 0.978723 (-8150 6050);
PAINT WHITE (-8150 6050);
DISPLAY INVISIBLE (-8150 6050);
FORCEPROP 1 LAST PART_NUMBER CS21002FB06
J 0
(-8160 5750);
DISPLAY 0.489362 (-8160 5750);
PAINT SKYBLUE (-8160 5750);
DISPLAY INVISIBLE (-8160 5750);
FORCEADD Q_RES..2
(-8375 5875);
FORCEPROP 1 LAST LOCATION R601
J 0
(-8350 5750);
DISPLAY 0.489362 (-8350 5750);
PAINT SKYBLUE (-8350 5750);
FORCEPROP 2 LAST $SEC 1
J 0
(-8325 6100);
DISPLAY 0.680851 (-8325 6100);
PAINT MONO (-8325 6100);
DISPLAY INVISIBLE (-8325 6100);
FORCEPROP 2 LAST CDS_SEC 1
J 0
(-8325 6100);
DISPLAY 0.680851 (-8325 6100);
DISPLAY INVISIBLE (-8325 6100);
FORCEPROP 1 LASTPIN (-8375 5975) $PN 1
J 0
(-8370 5937);
DISPLAY 0.489362 (-8370 5937);
PAINT MONO (-8370 5937);
FORCEPROP 1 LASTPIN (-8375 5775) $PN 2
J 0
(-8370 5785);
DISPLAY 0.489362 (-8370 5785);
PAINT MONO (-8370 5785);
FORCEPROP 1 LAST TOLERANCE 1%
J 0
(-8330 5900);
DISPLAY 0.489362 (-8330 5900);
PAINT SKYBLUE (-8330 5900);
FORCEPROP 1 LAST MATERIAL CHIP
J 0
(-8335 5800);
DISPLAY 0.489362 (-8335 5800);
PAINT SKYBLUE (-8335 5800);
FORCEPROP 1 LAST WATTAGE 1/16W
J 0
(-8335 5850);
DISPLAY 0.489362 (-8335 5850);
PAINT SKYBLUE (-8335 5850);
FORCEPROP 1 LAST VALUE 1K
J 0
(-8330 5950);
DISPLAY 0.489362 (-8330 5950);
PAINT SKYBLUE (-8330 5950);
FORCEPROP 2 LAST CDS_LIB pure_quanta
J 0
(-8375 5875);
DISPLAY INVISIBLE (-8375 5875);
FORCEPROP 1 LAST PACK_TYPE 0402LF
J 0
(-8325 5750);
DISPLAY 0.382979 (-8325 5750);
PAINT SKYBLUE (-8325 5750);
DISPLAY INVISIBLE (-8325 5750);
FORCEPROP 1 LAST PATH I108
J 0
(-8325 6050);
DISPLAY 0.978723 (-8325 6050);
PAINT WHITE (-8325 6050);
DISPLAY INVISIBLE (-8325 6050);
FORCEPROP 1 LAST PART_NUMBER CS21002FB06
J 0
(-8335 5750);
DISPLAY 0.489362 (-8335 5750);
PAINT SKYBLUE (-8335 5750);
DISPLAY INVISIBLE (-8335 5750);
FORCEADD OFFPAGE..2
(-7100 5575);
FORCEPROP 2 LAST $XR1 77 
J 0
(-6821 5575);
DISPLAY 0.638298 (-6821 5575);
PAINT MONO (-6821 5575);
FORCEPROP 2 LAST $XR0 29 
J 0
(-6911 5575);
DISPLAY 0.638298 (-6911 5575);
PAINT MONO (-6911 5575);
FORCEPROP 2 LAST CDS_LIB standard
J 0
(-7100 5575);
DISPLAY INVISIBLE (-7100 5575);
FORCEPROP 1 LAST OFFPAGE TRUE
J 0
(-6775 5450);
DISPLAY 0.872340 (-6775 5450);
PAINT GREEN (-6775 5450);
DISPLAY INVISIBLE (-6775 5450);
FORCEPROP 1 LAST COMMENT_BODY TRUE
J 0
(-7145 5480);
DISPLAY 0.872340 (-7145 5480);
PAINT PEACH (-7145 5480);
DISPLAY INVISIBLE (-7145 5480);
FORCEPROP 2 LAST PATH I109
J 0
(-6925 5650);
DISPLAY 1.021277 (-6925 5650);
DISPLAY INVISIBLE (-6925 5650);
FORCEADD OFFPAGE..2
(-7100 5525);
FORCEPROP 2 LAST $XR1 77 
J 0
(-6821 5525);
DISPLAY 0.638298 (-6821 5525);
PAINT MONO (-6821 5525);
FORCEPROP 2 LAST $XR0 29 
J 0
(-6911 5525);
DISPLAY 0.638298 (-6911 5525);
PAINT MONO (-6911 5525);
FORCEPROP 2 LAST CDS_LIB standard
J 0
(-7100 5525);
DISPLAY INVISIBLE (-7100 5525);
FORCEPROP 1 LAST OFFPAGE TRUE
J 0
(-6775 5400);
DISPLAY 0.872340 (-6775 5400);
PAINT GREEN (-6775 5400);
DISPLAY INVISIBLE (-6775 5400);
FORCEPROP 1 LAST COMMENT_BODY TRUE
J 0
(-7145 5430);
DISPLAY 0.872340 (-7145 5430);
PAINT PEACH (-7145 5430);
DISPLAY INVISIBLE (-7145 5430);
FORCEPROP 2 LAST PATH I110
J 0
(-6925 5600);
DISPLAY 1.021277 (-6925 5600);
DISPLAY INVISIBLE (-6925 5600);
FORCEADD OFFPAGE..2
(-7100 5475);
FORCEPROP 2 LAST $XR1 77 
J 0
(-6821 5475);
DISPLAY 0.638298 (-6821 5475);
PAINT MONO (-6821 5475);
FORCEPROP 2 LAST $XR0 29 
J 0
(-6911 5475);
DISPLAY 0.638298 (-6911 5475);
PAINT MONO (-6911 5475);
FORCEPROP 2 LAST CDS_LIB standard
J 0
(-7100 5475);
DISPLAY INVISIBLE (-7100 5475);
FORCEPROP 1 LAST OFFPAGE TRUE
J 0
(-6775 5350);
DISPLAY 0.872340 (-6775 5350);
PAINT GREEN (-6775 5350);
DISPLAY INVISIBLE (-6775 5350);
FORCEPROP 1 LAST COMMENT_BODY TRUE
J 0
(-7145 5380);
DISPLAY 0.872340 (-7145 5380);
PAINT PEACH (-7145 5380);
DISPLAY INVISIBLE (-7145 5380);
FORCEPROP 2 LAST PATH I111
J 0
(-6925 5550);
DISPLAY 1.021277 (-6925 5550);
DISPLAY INVISIBLE (-6925 5550);
FORCEADD Q_RES..2
R 2
(-2225 5625);
FORCEPROP 1 LAST LOCATION R20
J 0
(-2200 5725);
DISPLAY 0.489362 (-2200 5725);
PAINT SKYBLUE (-2200 5725);
FORCEPROP 0 LAST $SEC 1
J 0
(-2200 5750);
DISPLAY 0.680851 (-2200 5750);
PAINT MONO (-2200 5750);
DISPLAY INVISIBLE (-2200 5750);
FORCEPROP 0 LAST CDS_SEC 1
J 0
(-2200 5750);
DISPLAY 0.680851 (-2200 5750);
DISPLAY INVISIBLE (-2200 5750);
FORCEPROP 1 LASTPIN (-2225 5725) $PN 1
J 2
(-2230 5687);
DISPLAY 0.489362 (-2230 5687);
PAINT MONO (-2230 5687);
FORCEPROP 1 LASTPIN (-2225 5525) $PN 2
J 2
(-2230 5535);
DISPLAY 0.489362 (-2230 5535);
PAINT MONO (-2230 5535);
FORCEPROP 1 LAST MATERIAL CHIP
J 0
(-2200 5575);
DISPLAY 0.489362 (-2200 5575);
PAINT SKYBLUE (-2200 5575);
FORCEPROP 1 LAST TOLERANCE 1%
J 0
(-2200 5625);
DISPLAY 0.489362 (-2200 5625);
PAINT SKYBLUE (-2200 5625);
FORCEPROP 1 LAST VALUE 10K
J 0
(-2200 5675);
DISPLAY 0.489362 (-2200 5675);
PAINT SKYBLUE (-2200 5675);
FORCEPROP 2 LAST CDS_LIB pure_quanta
J 0
(-2225 5625);
DISPLAY INVISIBLE (-2225 5625);
FORCEPROP 1 LAST WATTAGE 1/16W
J 2
(-2275 5625);
DISPLAY 0.489362 (-2275 5625);
PAINT SKYBLUE (-2275 5625);
DISPLAY INVISIBLE (-2275 5625);
FORCEPROP 1 LAST PACK_TYPE 0402LF
J 2
(-2275 5575);
DISPLAY 0.489362 (-2275 5575);
PAINT SKYBLUE (-2275 5575);
DISPLAY INVISIBLE (-2275 5575);
FORCEPROP 1 LAST PATH I115
J 2
(-2275 5800);
DISPLAY 0.978723 (-2275 5800);
PAINT WHITE (-2275 5800);
DISPLAY INVISIBLE (-2275 5800);
FORCEPROP 1 LAST PART_NUMBER CS31002FB08
J 2
(-2275 5550);
DISPLAY 0.489362 (-2275 5550);
PAINT SKYBLUE (-2275 5550);
DISPLAY INVISIBLE (-2275 5550);
FORCEADD Q_RES..2
R 2
(-1875 5625);
FORCEPROP 1 LAST LOCATION R21
J 0
(-1850 5725);
DISPLAY 0.489362 (-1850 5725);
PAINT SKYBLUE (-1850 5725);
FORCEPROP 0 LAST $SEC 1
J 0
(-1850 5750);
DISPLAY 0.680851 (-1850 5750);
PAINT MONO (-1850 5750);
DISPLAY INVISIBLE (-1850 5750);
FORCEPROP 0 LAST CDS_SEC 1
J 0
(-1850 5750);
DISPLAY 0.680851 (-1850 5750);
DISPLAY INVISIBLE (-1850 5750);
FORCEPROP 1 LASTPIN (-1875 5725) $PN 1
J 2
(-1880 5687);
DISPLAY 0.489362 (-1880 5687);
PAINT MONO (-1880 5687);
FORCEPROP 1 LASTPIN (-1875 5525) $PN 2
J 2
(-1880 5535);
DISPLAY 0.489362 (-1880 5535);
PAINT MONO (-1880 5535);
FORCEPROP 1 LAST TOLERANCE 1%
J 0
(-1850 5625);
DISPLAY 0.489362 (-1850 5625);
PAINT SKYBLUE (-1850 5625);
FORCEPROP 1 LAST VALUE 1K
J 0
(-1850 5675);
DISPLAY 0.489362 (-1850 5675);
PAINT SKYBLUE (-1850 5675);
FORCEPROP 1 LAST MATERIAL EMPTY
J 0
(-1850 5575);
DISPLAY 0.489362 (-1850 5575);
PAINT RED (-1850 5575);
FORCEPROP 1 LAST PACK_TYPE 0402LF
J 2
(-1925 5575);
DISPLAY 0.489362 (-1925 5575);
PAINT SKYBLUE (-1925 5575);
DISPLAY INVISIBLE (-1925 5575);
FORCEPROP 1 LAST WATTAGE 1/16W
J 2
(-1925 5625);
DISPLAY 0.489362 (-1925 5625);
PAINT SKYBLUE (-1925 5625);
DISPLAY INVISIBLE (-1925 5625);
FORCEPROP 2 LAST CDS_LIB pure_quanta
J 0
(-1875 5625);
DISPLAY INVISIBLE (-1875 5625);
FORCEPROP 1 LAST PATH I116
J 2
(-1925 5800);
DISPLAY 0.978723 (-1925 5800);
PAINT WHITE (-1925 5800);
DISPLAY INVISIBLE (-1925 5800);
FORCEPROP 1 LAST PART_NUMBER CS21002FB06
J 2
(-1925 5550);
DISPLAY 0.489362 (-1925 5550);
PAINT SKYBLUE (-1925 5550);
DISPLAY INVISIBLE (-1925 5550);
FORCEADD Q_RES..2
R 2
(-1700 5625);
FORCEPROP 1 LAST LOCATION R127
J 0
(-1675 5725);
DISPLAY 0.489362 (-1675 5725);
PAINT SKYBLUE (-1675 5725);
FORCEPROP 0 LAST $SEC 1
J 0
(-1675 5750);
DISPLAY 0.680851 (-1675 5750);
PAINT MONO (-1675 5750);
DISPLAY INVISIBLE (-1675 5750);
FORCEPROP 0 LAST CDS_SEC 1
J 0
(-1675 5750);
DISPLAY 0.680851 (-1675 5750);
DISPLAY INVISIBLE (-1675 5750);
FORCEPROP 1 LASTPIN (-1700 5725) $PN 1
J 2
(-1705 5687);
DISPLAY 0.489362 (-1705 5687);
PAINT MONO (-1705 5687);
FORCEPROP 1 LASTPIN (-1700 5525) $PN 2
J 2
(-1705 5535);
DISPLAY 0.489362 (-1705 5535);
PAINT MONO (-1705 5535);
FORCEPROP 1 LAST TOLERANCE 1%
J 0
(-1675 5625);
DISPLAY 0.489362 (-1675 5625);
PAINT SKYBLUE (-1675 5625);
FORCEPROP 1 LAST VALUE 1K
J 0
(-1675 5675);
DISPLAY 0.489362 (-1675 5675);
PAINT SKYBLUE (-1675 5675);
FORCEPROP 1 LAST MATERIAL EMPTY
J 0
(-1675 5575);
DISPLAY 0.489362 (-1675 5575);
PAINT RED (-1675 5575);
FORCEPROP 1 LAST PACK_TYPE 0402LF
J 2
(-1750 5575);
DISPLAY 0.489362 (-1750 5575);
PAINT SKYBLUE (-1750 5575);
DISPLAY INVISIBLE (-1750 5575);
FORCEPROP 1 LAST WATTAGE 1/16W
J 2
(-1750 5625);
DISPLAY 0.489362 (-1750 5625);
PAINT SKYBLUE (-1750 5625);
DISPLAY INVISIBLE (-1750 5625);
FORCEPROP 2 LAST CDS_LIB pure_quanta
J 0
(-1700 5625);
DISPLAY INVISIBLE (-1700 5625);
FORCEPROP 1 LAST PATH I117
J 2
(-1750 5800);
DISPLAY 0.978723 (-1750 5800);
PAINT WHITE (-1750 5800);
DISPLAY INVISIBLE (-1750 5800);
FORCEPROP 1 LAST PART_NUMBER CS21002FB06
J 2
(-1750 5550);
DISPLAY 0.489362 (-1750 5550);
PAINT SKYBLUE (-1750 5550);
DISPLAY INVISIBLE (-1750 5550);
FORCEADD Q_RES..2
R 2
(-1525 5625);
FORCEPROP 1 LAST LOCATION R128
J 0
(-1500 5725);
DISPLAY 0.489362 (-1500 5725);
PAINT SKYBLUE (-1500 5725);
FORCEPROP 0 LAST $SEC 1
J 0
(-1500 5750);
DISPLAY 0.680851 (-1500 5750);
PAINT MONO (-1500 5750);
DISPLAY INVISIBLE (-1500 5750);
FORCEPROP 0 LAST CDS_SEC 1
J 0
(-1500 5750);
DISPLAY 0.680851 (-1500 5750);
DISPLAY INVISIBLE (-1500 5750);
FORCEPROP 1 LASTPIN (-1525 5725) $PN 1
J 2
(-1530 5687);
DISPLAY 0.489362 (-1530 5687);
PAINT MONO (-1530 5687);
FORCEPROP 1 LASTPIN (-1525 5525) $PN 2
J 2
(-1530 5535);
DISPLAY 0.489362 (-1530 5535);
PAINT MONO (-1530 5535);
FORCEPROP 1 LAST TOLERANCE 1%
J 0
(-1500 5625);
DISPLAY 0.489362 (-1500 5625);
PAINT SKYBLUE (-1500 5625);
FORCEPROP 1 LAST VALUE 1K
J 0
(-1500 5675);
DISPLAY 0.489362 (-1500 5675);
PAINT SKYBLUE (-1500 5675);
FORCEPROP 1 LAST MATERIAL EMPTY
J 0
(-1500 5575);
DISPLAY 0.489362 (-1500 5575);
PAINT RED (-1500 5575);
FORCEPROP 1 LAST PACK_TYPE 0402LF
J 2
(-1575 5575);
DISPLAY 0.489362 (-1575 5575);
PAINT SKYBLUE (-1575 5575);
DISPLAY INVISIBLE (-1575 5575);
FORCEPROP 1 LAST WATTAGE 1/16W
J 2
(-1575 5625);
DISPLAY 0.489362 (-1575 5625);
PAINT SKYBLUE (-1575 5625);
DISPLAY INVISIBLE (-1575 5625);
FORCEPROP 2 LAST CDS_LIB pure_quanta
J 0
(-1525 5625);
DISPLAY INVISIBLE (-1525 5625);
FORCEPROP 1 LAST PATH I118
J 2
(-1575 5800);
DISPLAY 0.978723 (-1575 5800);
PAINT WHITE (-1575 5800);
DISPLAY INVISIBLE (-1575 5800);
FORCEPROP 1 LAST PART_NUMBER CS21002FB06
J 2
(-1575 5550);
DISPLAY 0.489362 (-1575 5550);
PAINT SKYBLUE (-1575 5550);
DISPLAY INVISIBLE (-1575 5550);
FORCEADD Q_RES..2
R 2
(-1350 5625);
FORCEPROP 1 LAST LOCATION R129
J 0
(-1325 5725);
DISPLAY 0.489362 (-1325 5725);
PAINT SKYBLUE (-1325 5725);
FORCEPROP 0 LAST $SEC 1
J 0
(-1325 5750);
DISPLAY 0.680851 (-1325 5750);
PAINT MONO (-1325 5750);
DISPLAY INVISIBLE (-1325 5750);
FORCEPROP 0 LAST CDS_SEC 1
J 0
(-1325 5750);
DISPLAY 0.680851 (-1325 5750);
DISPLAY INVISIBLE (-1325 5750);
FORCEPROP 1 LASTPIN (-1350 5725) $PN 1
J 2
(-1355 5687);
DISPLAY 0.489362 (-1355 5687);
PAINT MONO (-1355 5687);
FORCEPROP 1 LASTPIN (-1350 5525) $PN 2
J 2
(-1355 5535);
DISPLAY 0.489362 (-1355 5535);
PAINT MONO (-1355 5535);
FORCEPROP 1 LAST TOLERANCE 1%
J 0
(-1325 5625);
DISPLAY 0.489362 (-1325 5625);
PAINT SKYBLUE (-1325 5625);
FORCEPROP 1 LAST VALUE 1K
J 0
(-1325 5675);
DISPLAY 0.489362 (-1325 5675);
PAINT SKYBLUE (-1325 5675);
FORCEPROP 1 LAST MATERIAL EMPTY
J 0
(-1325 5575);
DISPLAY 0.489362 (-1325 5575);
PAINT RED (-1325 5575);
FORCEPROP 1 LAST WATTAGE 1/16W
J 2
(-1400 5625);
DISPLAY 0.489362 (-1400 5625);
PAINT SKYBLUE (-1400 5625);
DISPLAY INVISIBLE (-1400 5625);
FORCEPROP 1 LAST PACK_TYPE 0402LF
J 2
(-1400 5575);
DISPLAY 0.489362 (-1400 5575);
PAINT SKYBLUE (-1400 5575);
DISPLAY INVISIBLE (-1400 5575);
FORCEPROP 2 LAST CDS_LIB pure_quanta
J 0
(-1350 5625);
DISPLAY INVISIBLE (-1350 5625);
FORCEPROP 1 LAST PATH I119
J 2
(-1400 5800);
DISPLAY 0.978723 (-1400 5800);
PAINT WHITE (-1400 5800);
DISPLAY INVISIBLE (-1400 5800);
FORCEPROP 1 LAST PART_NUMBER CS21002FB06
J 2
(-1400 5550);
DISPLAY 0.489362 (-1400 5550);
PAINT SKYBLUE (-1400 5550);
DISPLAY INVISIBLE (-1400 5550);
FORCEADD OFFPAGE..2
(-7100 5425);
FORCEPROP 2 LAST $XR1 77 
J 0
(-6821 5425);
DISPLAY 0.638298 (-6821 5425);
PAINT MONO (-6821 5425);
FORCEPROP 2 LAST $XR0 29 
J 0
(-6911 5425);
DISPLAY 0.638298 (-6911 5425);
PAINT MONO (-6911 5425);
FORCEPROP 2 LAST CDS_LIB standard
J 0
(-7100 5425);
DISPLAY INVISIBLE (-7100 5425);
FORCEPROP 1 LAST OFFPAGE TRUE
J 0
(-6775 5300);
DISPLAY 0.872340 (-6775 5300);
PAINT GREEN (-6775 5300);
DISPLAY INVISIBLE (-6775 5300);
FORCEPROP 1 LAST COMMENT_BODY TRUE
J 0
(-7145 5330);
DISPLAY 0.872340 (-7145 5330);
PAINT PEACH (-7145 5330);
DISPLAY INVISIBLE (-7145 5330);
FORCEPROP 2 LAST PATH I127
J 0
(-6925 5500);
DISPLAY 0.680851 (-6925 5500);
DISPLAY INVISIBLE (-6925 5500);
FORCEADD OFFPAGE..2
(-7100 5375);
FORCEPROP 2 LAST $XR1 77 
J 0
(-6821 5375);
DISPLAY 0.638298 (-6821 5375);
PAINT MONO (-6821 5375);
FORCEPROP 2 LAST $XR0 29 
J 0
(-6911 5375);
DISPLAY 0.638298 (-6911 5375);
PAINT MONO (-6911 5375);
FORCEPROP 2 LAST CDS_LIB standard
J 0
(-7100 5375);
DISPLAY INVISIBLE (-7100 5375);
FORCEPROP 1 LAST OFFPAGE TRUE
J 0
(-6775 5250);
DISPLAY 0.872340 (-6775 5250);
PAINT GREEN (-6775 5250);
DISPLAY INVISIBLE (-6775 5250);
FORCEPROP 1 LAST COMMENT_BODY TRUE
J 0
(-7145 5280);
DISPLAY 0.872340 (-7145 5280);
PAINT PEACH (-7145 5280);
DISPLAY INVISIBLE (-7145 5280);
FORCEPROP 2 LAST PATH I128
J 0
(-6925 5450);
DISPLAY 0.680851 (-6925 5450);
DISPLAY INVISIBLE (-6925 5450);
FORCEADD OFFPAGE..2
(-7100 5325);
FORCEPROP 2 LAST $XR1 77 
J 0
(-6821 5325);
DISPLAY 0.638298 (-6821 5325);
PAINT MONO (-6821 5325);
FORCEPROP 2 LAST $XR0 29 
J 0
(-6911 5325);
DISPLAY 0.638298 (-6911 5325);
PAINT MONO (-6911 5325);
FORCEPROP 2 LAST CDS_LIB standard
J 0
(-7100 5325);
DISPLAY INVISIBLE (-7100 5325);
FORCEPROP 1 LAST OFFPAGE TRUE
J 0
(-6775 5200);
DISPLAY 0.872340 (-6775 5200);
PAINT GREEN (-6775 5200);
DISPLAY INVISIBLE (-6775 5200);
FORCEPROP 1 LAST COMMENT_BODY TRUE
J 0
(-7145 5230);
DISPLAY 0.872340 (-7145 5230);
PAINT PEACH (-7145 5230);
DISPLAY INVISIBLE (-7145 5230);
FORCEPROP 2 LAST PATH I129
J 0
(-6925 5400);
DISPLAY 0.680851 (-6925 5400);
DISPLAY INVISIBLE (-6925 5400);
FORCEADD OFFPAGE..2
(-7100 5275);
FORCEPROP 2 LAST $XR1 77 
J 0
(-6821 5275);
DISPLAY 0.638298 (-6821 5275);
PAINT MONO (-6821 5275);
FORCEPROP 2 LAST $XR0 29 
J 0
(-6911 5275);
DISPLAY 0.638298 (-6911 5275);
PAINT MONO (-6911 5275);
FORCEPROP 2 LAST CDS_LIB standard
J 0
(-7100 5275);
DISPLAY INVISIBLE (-7100 5275);
FORCEPROP 1 LAST OFFPAGE TRUE
J 0
(-6775 5150);
DISPLAY 0.872340 (-6775 5150);
PAINT GREEN (-6775 5150);
DISPLAY INVISIBLE (-6775 5150);
FORCEPROP 1 LAST COMMENT_BODY TRUE
J 0
(-7145 5180);
DISPLAY 0.872340 (-7145 5180);
PAINT PEACH (-7145 5180);
DISPLAY INVISIBLE (-7145 5180);
FORCEPROP 2 LAST PATH I130
J 0
(-6925 5350);
DISPLAY 0.680851 (-6925 5350);
DISPLAY INVISIBLE (-6925 5350);
FORCEADD Q_RES..2
(-8550 5875);
FORCEPROP 1 LAST LOCATION R1532
J 0
(-8525 5750);
DISPLAY 0.489362 (-8525 5750);
PAINT SKYBLUE (-8525 5750);
FORCEPROP 0 LAST $SEC 1
J 0
(-8500 5975);
DISPLAY 0.680851 (-8500 5975);
PAINT MONO (-8500 5975);
DISPLAY INVISIBLE (-8500 5975);
FORCEPROP 0 LAST CDS_SEC 1
J 0
(-8500 5975);
DISPLAY 0.680851 (-8500 5975);
DISPLAY INVISIBLE (-8500 5975);
FORCEPROP 1 LASTPIN (-8550 5975) $PN 1
J 0
(-8545 5937);
DISPLAY 0.489362 (-8545 5937);
PAINT MONO (-8545 5937);
FORCEPROP 1 LASTPIN (-8550 5775) $PN 2
J 0
(-8545 5785);
DISPLAY 0.489362 (-8545 5785);
PAINT MONO (-8545 5785);
FORCEPROP 1 LAST TOLERANCE 1%
J 0
(-8505 5900);
DISPLAY 0.489362 (-8505 5900);
PAINT SKYBLUE (-8505 5900);
FORCEPROP 1 LAST WATTAGE 1/16W
J 0
(-8510 5850);
DISPLAY 0.489362 (-8510 5850);
PAINT SKYBLUE (-8510 5850);
FORCEPROP 1 LAST VALUE 1K
J 0
(-8505 5950);
DISPLAY 0.489362 (-8505 5950);
PAINT SKYBLUE (-8505 5950);
FORCEPROP 1 LAST MATERIAL EMPTY
J 0
(-8510 5800);
DISPLAY 0.489362 (-8510 5800);
PAINT RED (-8510 5800);
FORCEPROP 2 LAST CDS_LIB pure_quanta
J 0
(-8550 5875);
DISPLAY INVISIBLE (-8550 5875);
FORCEPROP 1 LAST PACK_TYPE 0402LF
J 0
(-8500 5750);
DISPLAY 0.382979 (-8500 5750);
PAINT SKYBLUE (-8500 5750);
DISPLAY INVISIBLE (-8500 5750);
FORCEPROP 1 LAST PATH I131
J 0
(-8500 6050);
DISPLAY 0.978723 (-8500 6050);
PAINT WHITE (-8500 6050);
DISPLAY INVISIBLE (-8500 6050);
FORCEPROP 1 LAST PART_NUMBER CS21002FB06
J 0
(-8510 5750);
DISPLAY 0.489362 (-8510 5750);
PAINT SKYBLUE (-8510 5750);
DISPLAY INVISIBLE (-8510 5750);
FORCEADD Q_RES..2
(-8725 5875);
FORCEPROP 1 LAST LOCATION R1531
J 0
(-8675 5750);
DISPLAY 0.489362 (-8675 5750);
PAINT SKYBLUE (-8675 5750);
FORCEPROP 0 LAST $SEC 1
J 0
(-8675 5975);
DISPLAY 0.680851 (-8675 5975);
PAINT MONO (-8675 5975);
DISPLAY INVISIBLE (-8675 5975);
FORCEPROP 0 LAST CDS_SEC 1
J 0
(-8675 5975);
DISPLAY 0.680851 (-8675 5975);
DISPLAY INVISIBLE (-8675 5975);
FORCEPROP 1 LASTPIN (-8725 5975) $PN 1
J 0
(-8720 5937);
DISPLAY 0.489362 (-8720 5937);
PAINT MONO (-8720 5937);
FORCEPROP 1 LASTPIN (-8725 5775) $PN 2
J 0
(-8720 5785);
DISPLAY 0.489362 (-8720 5785);
PAINT MONO (-8720 5785);
FORCEPROP 1 LAST TOLERANCE 1%
J 0
(-8680 5900);
DISPLAY 0.489362 (-8680 5900);
PAINT SKYBLUE (-8680 5900);
FORCEPROP 1 LAST VALUE 1K
J 0
(-8680 5950);
DISPLAY 0.489362 (-8680 5950);
PAINT SKYBLUE (-8680 5950);
FORCEPROP 1 LAST MATERIAL EMPTY
J 0
(-8685 5800);
DISPLAY 0.489362 (-8685 5800);
PAINT RED (-8685 5800);
FORCEPROP 1 LAST WATTAGE 1/16W
J 0
(-8685 5850);
DISPLAY 0.489362 (-8685 5850);
PAINT SKYBLUE (-8685 5850);
FORCEPROP 2 LAST CDS_LIB pure_quanta
J 0
(-8725 5875);
DISPLAY INVISIBLE (-8725 5875);
FORCEPROP 1 LAST PACK_TYPE 0402LF
J 0
(-8675 5750);
DISPLAY 0.382979 (-8675 5750);
PAINT SKYBLUE (-8675 5750);
DISPLAY INVISIBLE (-8675 5750);
FORCEPROP 1 LAST PATH I132
J 0
(-8675 6050);
DISPLAY 0.978723 (-8675 6050);
PAINT WHITE (-8675 6050);
DISPLAY INVISIBLE (-8675 6050);
FORCEPROP 1 LAST PART_NUMBER CS21002FB06
J 0
(-8685 5750);
DISPLAY 0.489362 (-8685 5750);
PAINT SKYBLUE (-8685 5750);
DISPLAY INVISIBLE (-8685 5750);
FORCEADD Q_RES..2
(-8900 5875);
FORCEPROP 1 LAST LOCATION R1530
J 0
(-8875 5750);
DISPLAY 0.489362 (-8875 5750);
PAINT SKYBLUE (-8875 5750);
FORCEPROP 0 LAST $SEC 1
J 0
(-8850 5975);
DISPLAY 0.680851 (-8850 5975);
PAINT MONO (-8850 5975);
DISPLAY INVISIBLE (-8850 5975);
FORCEPROP 0 LAST CDS_SEC 1
J 0
(-8850 5975);
DISPLAY 0.680851 (-8850 5975);
DISPLAY INVISIBLE (-8850 5975);
FORCEPROP 1 LASTPIN (-8900 5975) $PN 1
J 0
(-8895 5937);
DISPLAY 0.489362 (-8895 5937);
PAINT MONO (-8895 5937);
FORCEPROP 1 LASTPIN (-8900 5775) $PN 2
J 0
(-8895 5785);
DISPLAY 0.489362 (-8895 5785);
PAINT MONO (-8895 5785);
FORCEPROP 1 LAST TOLERANCE 1%
J 0
(-8855 5900);
DISPLAY 0.489362 (-8855 5900);
PAINT SKYBLUE (-8855 5900);
FORCEPROP 1 LAST VALUE 1K
J 0
(-8855 5950);
DISPLAY 0.489362 (-8855 5950);
PAINT SKYBLUE (-8855 5950);
FORCEPROP 1 LAST WATTAGE 1/16W
J 0
(-8860 5850);
DISPLAY 0.489362 (-8860 5850);
PAINT SKYBLUE (-8860 5850);
FORCEPROP 1 LAST MATERIAL EMPTY
J 0
(-8860 5800);
DISPLAY 0.489362 (-8860 5800);
PAINT RED (-8860 5800);
FORCEPROP 2 LAST CDS_LIB pure_quanta
J 0
(-8900 5875);
DISPLAY INVISIBLE (-8900 5875);
FORCEPROP 1 LAST PACK_TYPE 0402LF
J 0
(-8850 5750);
DISPLAY 0.382979 (-8850 5750);
PAINT SKYBLUE (-8850 5750);
DISPLAY INVISIBLE (-8850 5750);
FORCEPROP 1 LAST PATH I133
J 0
(-8850 6050);
DISPLAY 0.978723 (-8850 6050);
PAINT WHITE (-8850 6050);
DISPLAY INVISIBLE (-8850 6050);
FORCEPROP 1 LAST PART_NUMBER CS21002FB06
J 0
(-8860 5750);
DISPLAY 0.489362 (-8860 5750);
PAINT SKYBLUE (-8860 5750);
DISPLAY INVISIBLE (-8860 5750);
FORCEADD Q_RES..2
(-9075 5875);
FORCEPROP 1 LAST LOCATION R1529
J 0
(-9050 5750);
DISPLAY 0.489362 (-9050 5750);
PAINT SKYBLUE (-9050 5750);
FORCEPROP 0 LAST $SEC 1
J 0
(-9025 5975);
DISPLAY 0.680851 (-9025 5975);
PAINT MONO (-9025 5975);
DISPLAY INVISIBLE (-9025 5975);
FORCEPROP 0 LAST CDS_SEC 1
J 0
(-9025 5975);
DISPLAY 0.680851 (-9025 5975);
DISPLAY INVISIBLE (-9025 5975);
FORCEPROP 1 LASTPIN (-9075 5975) $PN 1
J 0
(-9070 5937);
DISPLAY 0.489362 (-9070 5937);
PAINT MONO (-9070 5937);
FORCEPROP 1 LASTPIN (-9075 5775) $PN 2
J 0
(-9070 5785);
DISPLAY 0.489362 (-9070 5785);
PAINT MONO (-9070 5785);
FORCEPROP 1 LAST TOLERANCE 1%
J 0
(-9030 5900);
DISPLAY 0.489362 (-9030 5900);
PAINT SKYBLUE (-9030 5900);
FORCEPROP 1 LAST WATTAGE 1/16W
J 0
(-9035 5850);
DISPLAY 0.489362 (-9035 5850);
PAINT SKYBLUE (-9035 5850);
FORCEPROP 1 LAST MATERIAL EMPTY
J 0
(-9035 5800);
DISPLAY 0.489362 (-9035 5800);
PAINT RED (-9035 5800);
FORCEPROP 1 LAST VALUE 1K
J 0
(-9030 5950);
DISPLAY 0.489362 (-9030 5950);
PAINT SKYBLUE (-9030 5950);
FORCEPROP 2 LAST CDS_LIB pure_quanta
J 0
(-9075 5875);
DISPLAY INVISIBLE (-9075 5875);
FORCEPROP 1 LAST PACK_TYPE 0402LF
J 0
(-9025 5750);
DISPLAY 0.382979 (-9025 5750);
PAINT SKYBLUE (-9025 5750);
DISPLAY INVISIBLE (-9025 5750);
FORCEPROP 1 LAST PATH I134
J 0
(-9025 6050);
DISPLAY 0.978723 (-9025 6050);
PAINT WHITE (-9025 6050);
DISPLAY INVISIBLE (-9025 6050);
FORCEPROP 1 LAST PART_NUMBER CS21002FB06
J 0
(-9035 5750);
DISPLAY 0.489362 (-9035 5750);
PAINT SKYBLUE (-9035 5750);
DISPLAY INVISIBLE (-9035 5750);
FORCEADD OFFPAGE..1
(-6925 2125);
FORCEPROP 2 LAST $XR1 81 
J 0
(-7266 2125);
DISPLAY 0.638298 (-7266 2125);
PAINT MONO (-7266 2125);
FORCEPROP 2 LAST $XR0 77 
J 0
(-7176 2125);
DISPLAY 0.638298 (-7176 2125);
PAINT MONO (-7176 2125);
FORCEPROP 2 LAST CDS_LIB standard
J 0
(-6925 2125);
DISPLAY INVISIBLE (-6925 2125);
FORCEPROP 1 LAST OFFPAGE TRUE
J 0
(-6595 1995);
PAINT GREEN (-6595 1995);
DISPLAY INVISIBLE (-6595 1995);
FORCEPROP 1 LAST COMMENT_BODY TRUE
J 0
(-6795 2025);
DISPLAY 1.106383 (-6795 2025);
PAINT PEACH (-6795 2025);
DISPLAY INVISIBLE (-6795 2025);
FORCEPROP 2 LAST PATH I136
J 0
(-7125 2175);
DISPLAY 0.680851 (-7125 2175);
DISPLAY INVISIBLE (-7125 2175);
FORCEADD UNIVERSAL_GND..1
(-6200 2500);
FORCEPROP 3 LASTPIN (-6200 2550) SIG_NAME GND\g
J 0
(-6190 2560);
DISPLAY 0.659574 (-6190 2560);
PAINT MONO (-6190 2560);
DISPLAY INVISIBLE (-6190 2560);
FORCEPROP 2 LAST CDS_LIB pure_quanta_power
J 0
(-6200 2500);
DISPLAY INVISIBLE (-6200 2500);
FORCEPROP 1 LAST HDL_POWER GND
J 1
(-6175 2425);
DISPLAY 0.872340 (-6175 2425);
PAINT GREEN (-6175 2425);
DISPLAY INVISIBLE (-6175 2425);
FORCEPROP 1 LAST PATH I138
J 0
(-6125 2500);
DISPLAY 0.872340 (-6125 2500);
PAINT AQUA (-6125 2500);
DISPLAY INVISIBLE (-6125 2500);
FORCEADD UNIVERSAL_GND..1
R 2
(-4725 2450);
FORCEPROP 3 LASTPIN (-4725 2500) SIG_NAME GND\g
J 0
(-4715 2510);
DISPLAY 0.659574 (-4715 2510);
PAINT MONO (-4715 2510);
DISPLAY INVISIBLE (-4715 2510);
FORCEPROP 2 LAST CDS_LIB pure_quanta_power
J 0
(-4725 2450);
DISPLAY INVISIBLE (-4725 2450);
FORCEPROP 1 LAST HDL_POWER GND
J 1
(-4750 2375);
DISPLAY 0.872340 (-4750 2375);
PAINT GREEN (-4750 2375);
DISPLAY INVISIBLE (-4750 2375);
FORCEPROP 1 LAST PATH I139
J 2
(-4800 2450);
DISPLAY 0.872340 (-4800 2450);
PAINT AQUA (-4800 2450);
DISPLAY INVISIBLE (-4800 2450);
FORCEADD Q_RES..2
(-1175 5625);
FORCEPROP 1 LAST LOCATION R1547
J 0
(-1150 5725);
DISPLAY 0.510638 (-1150 5725);
PAINT SKYBLUE (-1150 5725);
FORCEPROP 0 LAST $SEC 1
J 0
(-1150 5750);
DISPLAY 0.680851 (-1150 5750);
PAINT MONO (-1150 5750);
DISPLAY INVISIBLE (-1150 5750);
FORCEPROP 0 LAST CDS_SEC 1
J 0
(-1150 5750);
DISPLAY 0.680851 (-1150 5750);
DISPLAY INVISIBLE (-1150 5750);
FORCEPROP 1 LASTPIN (-1175 5725) $PN 1
J 0
(-1170 5687);
DISPLAY 0.787234 (-1170 5687);
PAINT MONO (-1170 5687);
FORCEPROP 1 LASTPIN (-1175 5525) $PN 2
J 0
(-1170 5535);
DISPLAY 0.787234 (-1170 5535);
PAINT MONO (-1170 5535);
FORCEPROP 1 LAST MATERIAL CHIP
J 0
(-1150 5575);
DISPLAY 0.510638 (-1150 5575);
PAINT SKYBLUE (-1150 5575);
FORCEPROP 1 LAST TOLERANCE 5%
J 0
(-1150 5625);
DISPLAY 0.510638 (-1150 5625);
PAINT SKYBLUE (-1150 5625);
FORCEPROP 1 LAST VALUE 4.7K
J 0
(-1150 5675);
DISPLAY 0.510638 (-1150 5675);
PAINT SKYBLUE (-1150 5675);
FORCEPROP 1 LAST PACK_TYPE 0402LF
J 0
(-1135 5450);
DISPLAY 0.978723 (-1135 5450);
DISPLAY INVISIBLE (-1135 5450);
FORCEPROP 1 LAST WATTAGE 1/16W
J 0
(-1135 5600);
DISPLAY 0.978723 (-1135 5600);
DISPLAY INVISIBLE (-1135 5600);
FORCEPROP 2 LAST CDS_LIB pure_quanta
J 0
(-1175 5625);
DISPLAY INVISIBLE (-1175 5625);
FORCEPROP 1 LAST PATH I148
J 0
(-1125 5800);
DISPLAY 0.978723 (-1125 5800);
PAINT WHITE (-1125 5800);
DISPLAY INVISIBLE (-1125 5800);
FORCEPROP 1 LAST PART_NUMBER CS24702JB10
J 0
(-1135 5500);
DISPLAY 0.978723 (-1135 5500);
DISPLAY INVISIBLE (-1135 5500);
FORCEADD OFFPAGE..2
R 2
(-3125 5150);
FORCEPROP 2 LAST $XR1 150 
J 0
(-3499 5150);
DISPLAY 0.638298 (-3499 5150);
PAINT MONO (-3499 5150);
FORCEPROP 2 LAST $XR0 77 
J 0
(-3379 5150);
DISPLAY 0.638298 (-3379 5150);
PAINT MONO (-3379 5150);
FORCEPROP 2 LAST CDS_LIB standard
J 0
(-3125 5150);
DISPLAY INVISIBLE (-3125 5150);
FORCEPROP 1 LAST OFFPAGE TRUE
J 2
(-3450 5025);
DISPLAY 0.872340 (-3450 5025);
PAINT GREEN (-3450 5025);
DISPLAY INVISIBLE (-3450 5025);
FORCEPROP 1 LAST COMMENT_BODY TRUE
J 2
(-3080 5055);
DISPLAY 0.872340 (-3080 5055);
PAINT PEACH (-3080 5055);
DISPLAY INVISIBLE (-3080 5055);
FORCEPROP 2 LAST PATH I149
J 0
(-3075 5225);
DISPLAY 0.680851 (-3075 5225);
DISPLAY INVISIBLE (-3075 5225);
FORCEADD Q_RES..2
(-9250 5875);
FORCEPROP 1 LAST LOCATION R1567
J 0
(-9225 5750);
DISPLAY 0.638298 (-9225 5750);
PAINT SKYBLUE (-9225 5750);
FORCEPROP 0 LAST $SEC 1
J 0
(-9225 5975);
DISPLAY 0.680851 (-9225 5975);
PAINT MONO (-9225 5975);
DISPLAY INVISIBLE (-9225 5975);
FORCEPROP 0 LAST CDS_SEC 1
J 0
(-9225 5975);
DISPLAY 0.680851 (-9225 5975);
DISPLAY INVISIBLE (-9225 5975);
FORCEPROP 1 LASTPIN (-9250 5975) $PN 1
J 0
(-9245 5937);
DISPLAY 0.787234 (-9245 5937);
PAINT MONO (-9245 5937);
FORCEPROP 1 LASTPIN (-9250 5775) $PN 2
J 0
(-9245 5785);
DISPLAY 0.787234 (-9245 5785);
PAINT MONO (-9245 5785);
FORCEPROP 1 LAST MATERIAL CHIP
J 0
(-9225 5800);
DISPLAY 0.510638 (-9225 5800);
PAINT SKYBLUE (-9225 5800);
FORCEPROP 1 LAST WATTAGE 1/16W
J 0
(-9225 5850);
DISPLAY 0.404255 (-9225 5850);
PAINT SKYBLUE (-9225 5850);
FORCEPROP 1 LAST TOLERANCE 5%
J 0
(-9225 5900);
DISPLAY 0.404255 (-9225 5900);
PAINT SKYBLUE (-9225 5900);
FORCEPROP 1 LAST VALUE 4.7K
J 0
(-9225 5950);
DISPLAY 0.404255 (-9225 5950);
PAINT SKYBLUE (-9225 5950);
FORCEPROP 2 LAST CDS_LIB pure_quanta
J 0
(-9250 5875);
DISPLAY INVISIBLE (-9250 5875);
FORCEPROP 1 LAST PACK_TYPE 0402LF
J 0
(-9210 5700);
DISPLAY 0.978723 (-9210 5700);
DISPLAY INVISIBLE (-9210 5700);
FORCEPROP 1 LAST PATH I150
J 0
(-9200 6050);
DISPLAY 0.978723 (-9200 6050);
PAINT WHITE (-9200 6050);
DISPLAY INVISIBLE (-9200 6050);
FORCEPROP 1 LAST PART_NUMBER CS24702JB10
J 0
(-9210 5750);
DISPLAY 0.978723 (-9210 5750);
DISPLAY INVISIBLE (-9210 5750);
FORCEADD OFFPAGE..2
(-7100 5225);
FORCEPROP 2 LAST $XR1 77 
J 0
(-6821 5225);
DISPLAY 0.638298 (-6821 5225);
PAINT MONO (-6821 5225);
FORCEPROP 2 LAST $XR0 81 
J 0
(-6911 5225);
DISPLAY 0.638298 (-6911 5225);
PAINT MONO (-6911 5225);
FORCEPROP 2 LAST CDS_LIB standard
J 0
(-7100 5225);
DISPLAY INVISIBLE (-7100 5225);
FORCEPROP 1 LAST OFFPAGE TRUE
J 0
(-6775 5100);
DISPLAY 0.872340 (-6775 5100);
PAINT GREEN (-6775 5100);
DISPLAY INVISIBLE (-6775 5100);
FORCEPROP 1 LAST COMMENT_BODY TRUE
J 0
(-7145 5130);
DISPLAY 0.872340 (-7145 5130);
PAINT PEACH (-7145 5130);
DISPLAY INVISIBLE (-7145 5130);
FORCEPROP 2 LAST PATH I151
J 0
(-6925 5300);
DISPLAY 0.680851 (-6925 5300);
DISPLAY INVISIBLE (-6925 5300);
FORCEADD OFFPAGE..1
(-6800 4225);
FORCEPROP 2 LAST $XR1 77 
J 0
(-7141 4225);
DISPLAY 0.638298 (-7141 4225);
PAINT MONO (-7141 4225);
FORCEPROP 2 LAST $XR0 29 
J 0
(-7051 4225);
DISPLAY 0.638298 (-7051 4225);
PAINT MONO (-7051 4225);
FORCEPROP 2 LAST CDS_LIB standard
J 0
(-6800 4225);
DISPLAY INVISIBLE (-6800 4225);
FORCEPROP 1 LAST OFFPAGE TRUE
J 0
(-6470 4095);
PAINT GREEN (-6470 4095);
DISPLAY INVISIBLE (-6470 4095);
FORCEPROP 1 LAST COMMENT_BODY TRUE
J 0
(-6670 4125);
DISPLAY 1.106383 (-6670 4125);
PAINT PEACH (-6670 4125);
DISPLAY INVISIBLE (-6670 4125);
FORCEPROP 2 LAST PATH I176
J 0
(-7050 4275);
DISPLAY 0.680851 (-7050 4275);
DISPLAY INVISIBLE (-7050 4275);
FORCEADD OFFPAGE..2
(-3000 4175);
FORCEPROP 2 LAST $XR1 150 
J 0
(-2721 4175);
DISPLAY 0.638298 (-2721 4175);
PAINT MONO (-2721 4175);
FORCEPROP 2 LAST $XR0 77 
J 0
(-2811 4175);
DISPLAY 0.638298 (-2811 4175);
PAINT MONO (-2811 4175);
FORCEPROP 2 LAST CDS_LIB standard
J 0
(-3000 4175);
DISPLAY INVISIBLE (-3000 4175);
FORCEPROP 1 LAST OFFPAGE TRUE
J 0
(-2675 4050);
DISPLAY 0.872340 (-2675 4050);
PAINT GREEN (-2675 4050);
DISPLAY INVISIBLE (-2675 4050);
FORCEPROP 1 LAST COMMENT_BODY TRUE
J 0
(-3045 4080);
DISPLAY 0.872340 (-3045 4080);
PAINT PEACH (-3045 4080);
DISPLAY INVISIBLE (-3045 4080);
FORCEPROP 2 LAST PATH I177
J 0
(-2700 4225);
DISPLAY 0.680851 (-2700 4225);
DISPLAY INVISIBLE (-2700 4225);
FORCEADD OFFPAGE..2
(-3000 4225);
FORCEPROP 2 LAST $XR0 77 
J 0
(-2811 4225);
DISPLAY 0.638298 (-2811 4225);
PAINT MONO (-2811 4225);
FORCEPROP 2 LAST CDS_LIB standard
J 0
(-3000 4225);
DISPLAY INVISIBLE (-3000 4225);
FORCEPROP 1 LAST OFFPAGE TRUE
J 0
(-2675 4100);
DISPLAY 0.872340 (-2675 4100);
PAINT GREEN (-2675 4100);
DISPLAY INVISIBLE (-2675 4100);
FORCEPROP 1 LAST COMMENT_BODY TRUE
J 0
(-3045 4130);
DISPLAY 0.872340 (-3045 4130);
PAINT PEACH (-3045 4130);
DISPLAY INVISIBLE (-3045 4130);
FORCEPROP 2 LAST PATH I179
J 0
(-2800 4275);
DISPLAY 0.680851 (-2800 4275);
DISPLAY INVISIBLE (-2800 4275);
FORCEADD Q_RES..1
(-3950 4225);
FORCEPROP 1 LAST LOCATION R600
J 0
(-3850 4225);
DISPLAY 0.489362 (-3850 4225);
PAINT SKYBLUE (-3850 4225);
FORCEPROP 0 LAST $SEC 1
J 0
(-3850 4250);
DISPLAY 0.680851 (-3850 4250);
PAINT MONO (-3850 4250);
DISPLAY INVISIBLE (-3850 4250);
FORCEPROP 0 LAST CDS_SEC 1
J 0
(-3850 4250);
DISPLAY 1.021277 (-3850 4250);
DISPLAY INVISIBLE (-3850 4250);
FORCEPROP 1 LASTPIN (-4050 4225) $PN 1
J 0
(-4038 4237);
DISPLAY 0.489362 (-4038 4237);
PAINT MONO (-4038 4237);
FORCEPROP 1 LASTPIN (-3850 4225) $PN 2
J 0
(-3888 4237);
DISPLAY 0.489362 (-3888 4237);
PAINT MONO (-3888 4237);
FORCEPROP 1 LAST VALUE 0
J 2
(-4050 4225);
DISPLAY 0.489362 (-4050 4225);
PAINT SKYBLUE (-4050 4225);
FORCEPROP 1 LAST PACK_TYPE 0402LF
J 0
(-3900 4150);
DISPLAY 0.489362 (-3900 4150);
PAINT SKYBLUE (-3900 4150);
DISPLAY INVISIBLE (-3900 4150);
FORCEPROP 1 LAST TOLERANCE 5%
J 0
(-3975 4150);
DISPLAY 0.489362 (-3975 4150);
PAINT SKYBLUE (-3975 4150);
DISPLAY INVISIBLE (-3975 4150);
FORCEPROP 1 LAST MATERIAL CHIP
J 0
(-3525 4150);
DISPLAY 0.489362 (-3525 4150);
PAINT SKYBLUE (-3525 4150);
DISPLAY INVISIBLE (-3525 4150);
FORCEPROP 1 LAST WATTAGE 1/16W
J 2
(-3550 4150);
DISPLAY 0.489362 (-3550 4150);
PAINT SKYBLUE (-3550 4150);
DISPLAY INVISIBLE (-3550 4150);
FORCEPROP 2 LAST CDS_LIB pure_quanta
J 0
(-3950 4225);
DISPLAY INVISIBLE (-3950 4225);
FORCEPROP 1 LAST PATH I180
J 0
(-4000 4375);
DISPLAY 0.978723 (-4000 4375);
PAINT WHITE (-4000 4375);
DISPLAY INVISIBLE (-4000 4375);
FORCEPROP 1 LAST PART_NUMBER CS00002JB13
J 0
(-3925 4275);
DISPLAY 0.489362 (-3925 4275);
PAINT SKYBLUE (-3925 4275);
DISPLAY INVISIBLE (-3925 4275);
FORCEADD OFFPAGE..1
(-6800 4175);
FORCEPROP 2 LAST $XR1 77 
J 0
(-7141 4175);
DISPLAY 0.638298 (-7141 4175);
PAINT MONO (-7141 4175);
FORCEPROP 2 LAST $XR0 29 
J 0
(-7051 4175);
DISPLAY 0.638298 (-7051 4175);
PAINT MONO (-7051 4175);
FORCEPROP 2 LAST CDS_LIB standard
J 0
(-6800 4175);
DISPLAY INVISIBLE (-6800 4175);
FORCEPROP 1 LAST OFFPAGE TRUE
J 0
(-6470 4045);
PAINT GREEN (-6470 4045);
DISPLAY INVISIBLE (-6470 4045);
FORCEPROP 1 LAST COMMENT_BODY TRUE
J 0
(-6670 4075);
DISPLAY 1.106383 (-6670 4075);
PAINT PEACH (-6670 4075);
DISPLAY INVISIBLE (-6670 4075);
FORCEPROP 2 LAST PATH I181
J 0
(-7075 4225);
DISPLAY 0.680851 (-7075 4225);
DISPLAY INVISIBLE (-7075 4225);
FORCEADD OFFPAGE..1
(-6800 3825);
FORCEPROP 2 LAST $XR0 81 
J 0
(-7051 3825);
DISPLAY 0.638298 (-7051 3825);
PAINT MONO (-7051 3825);
FORCEPROP 2 LAST CDS_LIB standard
J 0
(-6800 3825);
DISPLAY INVISIBLE (-6800 3825);
FORCEPROP 1 LAST OFFPAGE TRUE
J 0
(-6470 3695);
PAINT GREEN (-6470 3695);
DISPLAY INVISIBLE (-6470 3695);
FORCEPROP 1 LAST COMMENT_BODY TRUE
J 0
(-6670 3725);
DISPLAY 1.106383 (-6670 3725);
PAINT PEACH (-6670 3725);
DISPLAY INVISIBLE (-6670 3725);
FORCEPROP 2 LAST PATH I189
J 0
(-6750 3900);
DISPLAY 0.680851 (-6750 3900);
DISPLAY INVISIBLE (-6750 3900);
FORCEADD OFFPAGE..2
R 2
(-3125 5100);
FORCEPROP 2 LAST $XR0 77 
J 0
(-3379 5100);
DISPLAY 0.638298 (-3379 5100);
PAINT MONO (-3379 5100);
FORCEPROP 2 LAST CDS_LIB standard
J 0
(-3125 5100);
DISPLAY INVISIBLE (-3125 5100);
FORCEPROP 1 LAST OFFPAGE TRUE
J 2
(-3450 4975);
DISPLAY 0.872340 (-3450 4975);
PAINT GREEN (-3450 4975);
DISPLAY INVISIBLE (-3450 4975);
FORCEPROP 1 LAST COMMENT_BODY TRUE
J 2
(-3080 5005);
DISPLAY 0.872340 (-3080 5005);
PAINT PEACH (-3080 5005);
DISPLAY INVISIBLE (-3080 5005);
FORCEPROP 2 LAST PATH I190
J 0
(-3075 5175);
DISPLAY 0.680851 (-3075 5175);
DISPLAY INVISIBLE (-3075 5175);
FORCEADD Q_RES..2
R 2
(-1025 5625);
FORCEPROP 1 LAST LOCATION R1655
J 0
(-1000 5725);
DISPLAY 0.489362 (-1000 5725);
PAINT SKYBLUE (-1000 5725);
FORCEPROP 0 LAST $SEC 1
J 0
(-1000 5750);
DISPLAY 0.680851 (-1000 5750);
PAINT MONO (-1000 5750);
DISPLAY INVISIBLE (-1000 5750);
FORCEPROP 0 LAST CDS_SEC 1
J 0
(-1000 5750);
DISPLAY 0.680851 (-1000 5750);
DISPLAY INVISIBLE (-1000 5750);
FORCEPROP 1 LASTPIN (-1025 5725) $PN 1
J 2
(-1030 5687);
DISPLAY 0.787234 (-1030 5687);
PAINT MONO (-1030 5687);
FORCEPROP 1 LASTPIN (-1025 5525) $PN 2
J 2
(-1030 5535);
DISPLAY 0.787234 (-1030 5535);
PAINT MONO (-1030 5535);
FORCEPROP 1 LAST TOLERANCE 1%
J 0
(-1000 5625);
DISPLAY 0.489362 (-1000 5625);
PAINT SKYBLUE (-1000 5625);
FORCEPROP 1 LAST MATERIAL EMPTY
J 0
(-1000 5575);
DISPLAY 0.489362 (-1000 5575);
PAINT RED (-1000 5575);
FORCEPROP 1 LAST VALUE 1K
J 0
(-1000 5675);
DISPLAY 0.489362 (-1000 5675);
PAINT SKYBLUE (-1000 5675);
FORCEPROP 2 LAST CDS_LIB pure_quanta
J 0
(-1025 5625);
DISPLAY INVISIBLE (-1025 5625);
FORCEPROP 1 LAST WATTAGE 1/16W
J 2
(-1075 5625);
DISPLAY 0.489362 (-1075 5625);
PAINT SKYBLUE (-1075 5625);
DISPLAY INVISIBLE (-1075 5625);
FORCEPROP 1 LAST PACK_TYPE 0402LF
J 2
(-1075 5575);
DISPLAY 0.489362 (-1075 5575);
PAINT SKYBLUE (-1075 5575);
DISPLAY INVISIBLE (-1075 5575);
FORCEPROP 1 LAST PATH I191
J 2
(-1075 5800);
DISPLAY 0.978723 (-1075 5800);
PAINT WHITE (-1075 5800);
DISPLAY INVISIBLE (-1075 5800);
FORCEPROP 1 LAST PART_NUMBER CS21002FB06
J 2
(-1075 5550);
DISPLAY 0.489362 (-1075 5550);
PAINT SKYBLUE (-1075 5550);
DISPLAY INVISIBLE (-1075 5550);
FORCEADD UNIVERSAL_POWER..1
(-6225 4100);
FORCEPROP 3 LASTPIN (-6225 4050) SIG_NAME PVDD18_S5_P0\g
J 0
(-6215 4060);
DISPLAY 0.659574 (-6215 4060);
PAINT MONO (-6215 4060);
DISPLAY INVISIBLE (-6215 4060);
FORCEPROP 1 LAST HDL_POWER PVDD18_S5_P0
J 1
(-6225 4150);
DISPLAY 0.489362 (-6225 4150);
PAINT GREEN (-6225 4150);
FORCEPROP 2 LAST CDS_LIB pure_quanta_power
J 0
(-6225 4100);
DISPLAY INVISIBLE (-6225 4100);
FORCEPROP 1 LAST PATH I192
J 0
(-6175 4125);
DISPLAY 0.872340 (-6175 4125);
PAINT AQUA (-6175 4125);
DISPLAY INVISIBLE (-6175 4125);
FORCEADD Q_RES..1
(-4075 2325);
FORCEPROP 1 LAST LOCATION R606
J 0
(-3975 2325);
DISPLAY 0.489362 (-3975 2325);
PAINT SKYBLUE (-3975 2325);
FORCEPROP 0 LAST $SEC 1
J 0
(-3975 2350);
DISPLAY 0.680851 (-3975 2350);
PAINT MONO (-3975 2350);
DISPLAY INVISIBLE (-3975 2350);
FORCEPROP 0 LAST CDS_SEC 1
J 0
(-3975 2350);
DISPLAY 1.021277 (-3975 2350);
DISPLAY INVISIBLE (-3975 2350);
FORCEPROP 1 LASTPIN (-4175 2325) $PN 1
J 0
(-4163 2337);
DISPLAY 0.489362 (-4163 2337);
PAINT MONO (-4163 2337);
FORCEPROP 1 LASTPIN (-3975 2325) $PN 2
J 0
(-4013 2337);
DISPLAY 0.489362 (-4013 2337);
PAINT MONO (-4013 2337);
FORCEPROP 1 LAST VALUE 0
J 2
(-4175 2325);
DISPLAY 0.489362 (-4175 2325);
PAINT SKYBLUE (-4175 2325);
FORCEPROP 1 LAST PACK_TYPE 0402LF
J 0
(-4025 2250);
DISPLAY 0.489362 (-4025 2250);
PAINT SKYBLUE (-4025 2250);
DISPLAY INVISIBLE (-4025 2250);
FORCEPROP 1 LAST TOLERANCE 5%
J 0
(-4100 2250);
DISPLAY 0.489362 (-4100 2250);
PAINT SKYBLUE (-4100 2250);
DISPLAY INVISIBLE (-4100 2250);
FORCEPROP 1 LAST MATERIAL CHIP
J 0
(-3650 2250);
DISPLAY 0.489362 (-3650 2250);
PAINT SKYBLUE (-3650 2250);
DISPLAY INVISIBLE (-3650 2250);
FORCEPROP 1 LAST WATTAGE 1/16W
J 2
(-3675 2250);
DISPLAY 0.489362 (-3675 2250);
PAINT SKYBLUE (-3675 2250);
DISPLAY INVISIBLE (-3675 2250);
FORCEPROP 2 LAST CDS_LIB pure_quanta
J 0
(-4075 2325);
DISPLAY INVISIBLE (-4075 2325);
FORCEPROP 1 LAST PATH I205
J 0
(-4125 2475);
DISPLAY 0.978723 (-4125 2475);
PAINT WHITE (-4125 2475);
DISPLAY INVISIBLE (-4125 2475);
FORCEPROP 1 LAST PART_NUMBER CS00002JB13
J 0
(-4050 2375);
DISPLAY 0.489362 (-4050 2375);
PAINT SKYBLUE (-4050 2375);
DISPLAY INVISIBLE (-4050 2375);
FORCEADD OFFPAGE..3
(-3125 2325);
FORCEPROP 2 LAST $XR1 150 
J 0
(-2821 2325);
DISPLAY 0.638298 (-2821 2325);
PAINT MONO (-2821 2325);
FORCEPROP 2 LAST $XR0 77 
J 0
(-2911 2325);
DISPLAY 0.638298 (-2911 2325);
PAINT MONO (-2911 2325);
FORCEPROP 2 LAST CDS_LIB standard
J 0
(-3125 2325);
DISPLAY INVISIBLE (-3125 2325);
FORCEPROP 1 LAST OFFPAGE TRUE
J 0
(-2800 2200);
DISPLAY 0.872340 (-2800 2200);
PAINT GREEN (-2800 2200);
DISPLAY INVISIBLE (-2800 2200);
FORCEPROP 1 LAST COMMENT_BODY TRUE
J 0
(-3175 2225);
DISPLAY 0.872340 (-3175 2225);
PAINT PEACH (-3175 2225);
DISPLAY INVISIBLE (-3175 2225);
FORCEPROP 2 LAST PATH I206
J 0
(-2800 2375);
DISPLAY 0.680851 (-2800 2375);
DISPLAY INVISIBLE (-2800 2375);
FORCEADD Q_RES..1
(-4075 2375);
FORCEPROP 1 LAST LOCATION R607
J 0
(-3975 2375);
DISPLAY 0.489362 (-3975 2375);
PAINT SKYBLUE (-3975 2375);
FORCEPROP 0 LAST $SEC 1
J 0
(-3975 2400);
DISPLAY 0.680851 (-3975 2400);
PAINT MONO (-3975 2400);
DISPLAY INVISIBLE (-3975 2400);
FORCEPROP 0 LAST CDS_SEC 1
J 0
(-3975 2400);
DISPLAY 1.021277 (-3975 2400);
DISPLAY INVISIBLE (-3975 2400);
FORCEPROP 1 LASTPIN (-4175 2375) $PN 1
J 0
(-4163 2387);
DISPLAY 0.489362 (-4163 2387);
PAINT MONO (-4163 2387);
FORCEPROP 1 LASTPIN (-3975 2375) $PN 2
J 0
(-4013 2387);
DISPLAY 0.489362 (-4013 2387);
PAINT MONO (-4013 2387);
FORCEPROP 1 LAST VALUE 0
J 2
(-4175 2375);
DISPLAY 0.489362 (-4175 2375);
PAINT SKYBLUE (-4175 2375);
FORCEPROP 1 LAST WATTAGE 1/16W
J 2
(-3675 2300);
DISPLAY 0.489362 (-3675 2300);
PAINT SKYBLUE (-3675 2300);
DISPLAY INVISIBLE (-3675 2300);
FORCEPROP 1 LAST MATERIAL CHIP
J 0
(-3650 2300);
DISPLAY 0.489362 (-3650 2300);
PAINT SKYBLUE (-3650 2300);
DISPLAY INVISIBLE (-3650 2300);
FORCEPROP 1 LAST TOLERANCE 5%
J 0
(-4100 2300);
DISPLAY 0.489362 (-4100 2300);
PAINT SKYBLUE (-4100 2300);
DISPLAY INVISIBLE (-4100 2300);
FORCEPROP 1 LAST PACK_TYPE 0402LF
J 0
(-4025 2300);
DISPLAY 0.489362 (-4025 2300);
PAINT SKYBLUE (-4025 2300);
DISPLAY INVISIBLE (-4025 2300);
FORCEPROP 2 LAST CDS_LIB pure_quanta
J 0
(-4075 2375);
DISPLAY INVISIBLE (-4075 2375);
FORCEPROP 1 LAST PATH I207
J 0
(-4125 2525);
DISPLAY 0.978723 (-4125 2525);
PAINT WHITE (-4125 2525);
DISPLAY INVISIBLE (-4125 2525);
FORCEPROP 1 LAST PART_NUMBER CS00002JB13
J 0
(-4050 2425);
DISPLAY 0.489362 (-4050 2425);
PAINT SKYBLUE (-4050 2425);
DISPLAY INVISIBLE (-4050 2425);
FORCEADD OFFPAGE..3
(-3125 2375);
FORCEPROP 2 LAST $XR1 150 
J 0
(-2821 2375);
DISPLAY 0.638298 (-2821 2375);
PAINT MONO (-2821 2375);
FORCEPROP 2 LAST $XR0 77 
J 0
(-2911 2375);
DISPLAY 0.638298 (-2911 2375);
PAINT MONO (-2911 2375);
FORCEPROP 2 LAST CDS_LIB standard
J 0
(-3125 2375);
DISPLAY INVISIBLE (-3125 2375);
FORCEPROP 1 LAST OFFPAGE TRUE
J 0
(-2800 2250);
DISPLAY 0.872340 (-2800 2250);
PAINT GREEN (-2800 2250);
DISPLAY INVISIBLE (-2800 2250);
FORCEPROP 1 LAST COMMENT_BODY TRUE
J 0
(-3175 2275);
DISPLAY 0.872340 (-3175 2275);
PAINT PEACH (-3175 2275);
DISPLAY INVISIBLE (-3175 2275);
FORCEPROP 2 LAST PATH I208
J 0
(-2800 2425);
DISPLAY 0.680851 (-2800 2425);
DISPLAY INVISIBLE (-2800 2425);
FORCEADD OFFPAGE..3
(-3125 2225);
FORCEPROP 2 LAST $XR1 150 
J 0
(-2821 2225);
DISPLAY 0.638298 (-2821 2225);
PAINT MONO (-2821 2225);
FORCEPROP 2 LAST $XR0 77 
J 0
(-2911 2225);
DISPLAY 0.638298 (-2911 2225);
PAINT MONO (-2911 2225);
FORCEPROP 2 LAST CDS_LIB standard
J 2
(-3125 2225);
DISPLAY INVISIBLE (-3125 2225);
FORCEPROP 1 LAST OFFPAGE TRUE
J 0
(-2800 2100);
DISPLAY 0.872340 (-2800 2100);
PAINT GREEN (-2800 2100);
DISPLAY INVISIBLE (-2800 2100);
FORCEPROP 1 LAST COMMENT_BODY TRUE
J 0
(-3175 2125);
DISPLAY 0.872340 (-3175 2125);
PAINT PEACH (-3175 2125);
DISPLAY INVISIBLE (-3175 2125);
FORCEPROP 2 LAST PATH I218
J 0
(-2800 2275);
DISPLAY 0.680851 (-2800 2275);
DISPLAY INVISIBLE (-2800 2275);
FORCEADD Q_RES..1
(-4075 2225);
FORCEPROP 1 LAST LOCATION R605
J 0
(-3975 2225);
DISPLAY 0.489362 (-3975 2225);
PAINT SKYBLUE (-3975 2225);
FORCEPROP 0 LAST $SEC 1
J 0
(-3975 2250);
DISPLAY 0.680851 (-3975 2250);
PAINT MONO (-3975 2250);
DISPLAY INVISIBLE (-3975 2250);
FORCEPROP 0 LAST CDS_SEC 1
J 0
(-3975 2250);
DISPLAY 1.021277 (-3975 2250);
DISPLAY INVISIBLE (-3975 2250);
FORCEPROP 1 LASTPIN (-4175 2225) $PN 1
J 0
(-4163 2237);
DISPLAY 0.489362 (-4163 2237);
PAINT MONO (-4163 2237);
FORCEPROP 1 LASTPIN (-3975 2225) $PN 2
J 0
(-4013 2237);
DISPLAY 0.489362 (-4013 2237);
PAINT MONO (-4013 2237);
FORCEPROP 1 LAST VALUE 49.9
J 2
(-4175 2225);
DISPLAY 0.489362 (-4175 2225);
PAINT SKYBLUE (-4175 2225);
FORCEPROP 1 LAST TOLERANCE 1%
J 0
(-4100 2150);
DISPLAY 0.489362 (-4100 2150);
PAINT SKYBLUE (-4100 2150);
DISPLAY INVISIBLE (-4100 2150);
FORCEPROP 2 LAST CDS_LIB pure_quanta
J 0
(-4075 2225);
DISPLAY INVISIBLE (-4075 2225);
FORCEPROP 1 LAST WATTAGE 1/16W
J 2
(-3675 2150);
DISPLAY 0.489362 (-3675 2150);
PAINT SKYBLUE (-3675 2150);
DISPLAY INVISIBLE (-3675 2150);
FORCEPROP 1 LAST MATERIAL CHIP
J 0
(-3650 2150);
DISPLAY 0.489362 (-3650 2150);
PAINT SKYBLUE (-3650 2150);
DISPLAY INVISIBLE (-3650 2150);
FORCEPROP 1 LAST PACK_TYPE 0402LF
J 0
(-4025 2150);
DISPLAY 0.489362 (-4025 2150);
PAINT SKYBLUE (-4025 2150);
DISPLAY INVISIBLE (-4025 2150);
FORCEPROP 1 LAST PATH I219
J 0
(-4125 2375);
DISPLAY 0.978723 (-4125 2375);
PAINT WHITE (-4125 2375);
DISPLAY INVISIBLE (-4125 2375);
FORCEPROP 1 LAST PART_NUMBER CS04992FB07
J 0
(-4050 2275);
DISPLAY 0.489362 (-4050 2275);
PAINT SKYBLUE (-4050 2275);
DISPLAY INVISIBLE (-4050 2275);
FORCEADD OFFPAGE..3
(-3125 2275);
FORCEPROP 2 LAST $XR1 150 
J 0
(-2821 2275);
DISPLAY 0.638298 (-2821 2275);
PAINT MONO (-2821 2275);
FORCEPROP 2 LAST $XR0 77 
J 0
(-2911 2275);
DISPLAY 0.638298 (-2911 2275);
PAINT MONO (-2911 2275);
FORCEPROP 2 LAST CDS_LIB standard
J 2
(-3125 2275);
DISPLAY INVISIBLE (-3125 2275);
FORCEPROP 1 LAST OFFPAGE TRUE
J 0
(-2800 2150);
DISPLAY 0.872340 (-2800 2150);
PAINT GREEN (-2800 2150);
DISPLAY INVISIBLE (-2800 2150);
FORCEPROP 1 LAST COMMENT_BODY TRUE
J 0
(-3175 2175);
DISPLAY 0.872340 (-3175 2175);
PAINT PEACH (-3175 2175);
DISPLAY INVISIBLE (-3175 2175);
FORCEPROP 2 LAST PATH I220
J 0
(-2800 2325);
DISPLAY 0.680851 (-2800 2325);
DISPLAY INVISIBLE (-2800 2325);
FORCEADD Q_RES..1
(-4075 2275);
FORCEPROP 1 LAST LOCATION R604
J 0
(-3975 2275);
DISPLAY 0.489362 (-3975 2275);
PAINT SKYBLUE (-3975 2275);
FORCEPROP 0 LAST $SEC 1
J 0
(-3975 2300);
DISPLAY 0.680851 (-3975 2300);
PAINT MONO (-3975 2300);
DISPLAY INVISIBLE (-3975 2300);
FORCEPROP 0 LAST CDS_SEC 1
J 0
(-3975 2300);
DISPLAY 1.021277 (-3975 2300);
DISPLAY INVISIBLE (-3975 2300);
FORCEPROP 1 LASTPIN (-4175 2275) $PN 1
J 0
(-4163 2287);
DISPLAY 0.489362 (-4163 2287);
PAINT MONO (-4163 2287);
FORCEPROP 1 LASTPIN (-3975 2275) $PN 2
J 0
(-4013 2287);
DISPLAY 0.489362 (-4013 2287);
PAINT MONO (-4013 2287);
FORCEPROP 1 LAST VALUE 33.2
J 2
(-4175 2275);
DISPLAY 0.489362 (-4175 2275);
PAINT SKYBLUE (-4175 2275);
FORCEPROP 1 LAST TOLERANCE 1%
J 0
(-4100 2200);
DISPLAY 0.489362 (-4100 2200);
PAINT SKYBLUE (-4100 2200);
DISPLAY INVISIBLE (-4100 2200);
FORCEPROP 2 LAST CDS_LIB pure_quanta
J 0
(-4075 2275);
DISPLAY INVISIBLE (-4075 2275);
FORCEPROP 1 LAST WATTAGE 1/16W
J 2
(-3675 2200);
DISPLAY 0.489362 (-3675 2200);
PAINT SKYBLUE (-3675 2200);
DISPLAY INVISIBLE (-3675 2200);
FORCEPROP 1 LAST MATERIAL CHIP
J 0
(-3650 2200);
DISPLAY 0.489362 (-3650 2200);
PAINT SKYBLUE (-3650 2200);
DISPLAY INVISIBLE (-3650 2200);
FORCEPROP 1 LAST PACK_TYPE 0402LF
J 0
(-4025 2200);
DISPLAY 0.489362 (-4025 2200);
PAINT SKYBLUE (-4025 2200);
DISPLAY INVISIBLE (-4025 2200);
FORCEPROP 1 LAST PATH I221
J 0
(-4125 2425);
DISPLAY 0.978723 (-4125 2425);
PAINT WHITE (-4125 2425);
DISPLAY INVISIBLE (-4125 2425);
FORCEPROP 1 LAST PART_NUMBER CS03322FB03
J 0
(-4050 2325);
DISPLAY 0.489362 (-4050 2325);
PAINT SKYBLUE (-4050 2325);
DISPLAY INVISIBLE (-4050 2325);
FORCEADD OFFPAGE..2
(-3000 4325);
FORCEPROP 2 LAST $XR1 150 
J 0
(-2721 4325);
DISPLAY 0.638298 (-2721 4325);
PAINT MONO (-2721 4325);
FORCEPROP 2 LAST $XR0 77 
J 0
(-2811 4325);
DISPLAY 0.638298 (-2811 4325);
PAINT MONO (-2811 4325);
FORCEPROP 2 LAST CDS_LIB standard
J 0
(-3000 4325);
DISPLAY INVISIBLE (-3000 4325);
FORCEPROP 1 LAST OFFPAGE TRUE
J 0
(-2675 4200);
DISPLAY 0.872340 (-2675 4200);
PAINT GREEN (-2675 4200);
DISPLAY INVISIBLE (-2675 4200);
FORCEPROP 1 LAST COMMENT_BODY TRUE
J 0
(-3045 4230);
DISPLAY 0.872340 (-3045 4230);
PAINT PEACH (-3045 4230);
DISPLAY INVISIBLE (-3045 4230);
FORCEPROP 2 LAST PATH I227
J 0
(-2700 4375);
DISPLAY 0.680851 (-2700 4375);
DISPLAY INVISIBLE (-2700 4375);
FORCEADD Q_RES..1
(-3950 4325);
FORCEPROP 1 LAST LOCATION R603
J 0
(-3850 4325);
DISPLAY 0.489362 (-3850 4325);
PAINT SKYBLUE (-3850 4325);
FORCEPROP 0 LAST $SEC 1
J 0
(-3850 4350);
DISPLAY 0.680851 (-3850 4350);
PAINT MONO (-3850 4350);
DISPLAY INVISIBLE (-3850 4350);
FORCEPROP 0 LAST CDS_SEC 1
J 0
(-3850 4350);
DISPLAY 1.021277 (-3850 4350);
DISPLAY INVISIBLE (-3850 4350);
FORCEPROP 1 LASTPIN (-4050 4325) $PN 1
J 0
(-4038 4337);
DISPLAY 0.489362 (-4038 4337);
PAINT MONO (-4038 4337);
FORCEPROP 1 LASTPIN (-3850 4325) $PN 2
J 0
(-3888 4337);
DISPLAY 0.489362 (-3888 4337);
PAINT MONO (-3888 4337);
FORCEPROP 1 LAST VALUE 0
J 2
(-4050 4325);
DISPLAY 0.489362 (-4050 4325);
PAINT SKYBLUE (-4050 4325);
FORCEPROP 2 LAST CDS_LIB pure_quanta
J 0
(-3950 4325);
DISPLAY INVISIBLE (-3950 4325);
FORCEPROP 1 LAST WATTAGE 1/16W
J 2
(-3550 4250);
DISPLAY 0.489362 (-3550 4250);
PAINT SKYBLUE (-3550 4250);
DISPLAY INVISIBLE (-3550 4250);
FORCEPROP 1 LAST MATERIAL CHIP
J 0
(-3525 4250);
DISPLAY 0.489362 (-3525 4250);
PAINT SKYBLUE (-3525 4250);
DISPLAY INVISIBLE (-3525 4250);
FORCEPROP 1 LAST TOLERANCE 5%
J 0
(-3975 4250);
DISPLAY 0.489362 (-3975 4250);
PAINT SKYBLUE (-3975 4250);
DISPLAY INVISIBLE (-3975 4250);
FORCEPROP 1 LAST PACK_TYPE 0402LF
J 0
(-3900 4250);
DISPLAY 0.489362 (-3900 4250);
PAINT SKYBLUE (-3900 4250);
DISPLAY INVISIBLE (-3900 4250);
FORCEPROP 1 LAST PATH I228
J 0
(-4000 4475);
DISPLAY 0.978723 (-4000 4475);
PAINT WHITE (-4000 4475);
DISPLAY INVISIBLE (-4000 4475);
FORCEPROP 1 LAST PART_NUMBER CS00002JB13
J 0
(-3925 4375);
DISPLAY 0.489362 (-3925 4375);
PAINT SKYBLUE (-3925 4375);
DISPLAY INVISIBLE (-3925 4375);
FORCEADD OFFPAGE..2
(-3000 4275);
FORCEPROP 2 LAST $XR1 150 
J 0
(-2721 4275);
DISPLAY 0.638298 (-2721 4275);
PAINT MONO (-2721 4275);
FORCEPROP 2 LAST $XR0 77 
J 0
(-2811 4275);
DISPLAY 0.638298 (-2811 4275);
PAINT MONO (-2811 4275);
FORCEPROP 2 LAST CDS_LIB standard
J 0
(-3000 4275);
DISPLAY INVISIBLE (-3000 4275);
FORCEPROP 1 LAST OFFPAGE TRUE
J 0
(-2675 4150);
DISPLAY 0.872340 (-2675 4150);
PAINT GREEN (-2675 4150);
DISPLAY INVISIBLE (-2675 4150);
FORCEPROP 1 LAST COMMENT_BODY TRUE
J 0
(-3045 4180);
DISPLAY 0.872340 (-3045 4180);
PAINT PEACH (-3045 4180);
DISPLAY INVISIBLE (-3045 4180);
FORCEPROP 2 LAST PATH I229
J 0
(-2700 4325);
DISPLAY 0.680851 (-2700 4325);
DISPLAY INVISIBLE (-2700 4325);
FORCEADD Q_RES..1
(-3950 4275);
FORCEPROP 1 LAST LOCATION R602
J 0
(-3850 4275);
DISPLAY 0.489362 (-3850 4275);
PAINT SKYBLUE (-3850 4275);
FORCEPROP 0 LAST $SEC 1
J 0
(-3850 4300);
DISPLAY 0.680851 (-3850 4300);
PAINT MONO (-3850 4300);
DISPLAY INVISIBLE (-3850 4300);
FORCEPROP 0 LAST CDS_SEC 1
J 0
(-3850 4300);
DISPLAY 1.021277 (-3850 4300);
DISPLAY INVISIBLE (-3850 4300);
FORCEPROP 1 LASTPIN (-4050 4275) $PN 1
J 0
(-4038 4287);
DISPLAY 0.489362 (-4038 4287);
PAINT MONO (-4038 4287);
FORCEPROP 1 LASTPIN (-3850 4275) $PN 2
J 0
(-3888 4287);
DISPLAY 0.489362 (-3888 4287);
PAINT MONO (-3888 4287);
FORCEPROP 1 LAST VALUE 33
J 2
(-4050 4275);
DISPLAY 0.489362 (-4050 4275);
PAINT SKYBLUE (-4050 4275);
FORCEPROP 1 LAST WATTAGE 1/16W
J 2
(-3550 4200);
DISPLAY 0.489362 (-3550 4200);
PAINT SKYBLUE (-3550 4200);
DISPLAY INVISIBLE (-3550 4200);
FORCEPROP 1 LAST MATERIAL CHIP
J 0
(-3525 4200);
DISPLAY 0.489362 (-3525 4200);
PAINT SKYBLUE (-3525 4200);
DISPLAY INVISIBLE (-3525 4200);
FORCEPROP 1 LAST TOLERANCE 5%
J 0
(-3975 4200);
DISPLAY 0.489362 (-3975 4200);
PAINT SKYBLUE (-3975 4200);
DISPLAY INVISIBLE (-3975 4200);
FORCEPROP 1 LAST PACK_TYPE 0402LF
J 0
(-3900 4200);
DISPLAY 0.489362 (-3900 4200);
PAINT SKYBLUE (-3900 4200);
DISPLAY INVISIBLE (-3900 4200);
FORCEPROP 2 LAST CDS_LIB pure_quanta
J 0
(-3950 4275);
DISPLAY INVISIBLE (-3950 4275);
FORCEPROP 1 LAST PATH I230
J 0
(-4000 4425);
DISPLAY 0.978723 (-4000 4425);
PAINT WHITE (-4000 4425);
DISPLAY INVISIBLE (-4000 4425);
FORCEPROP 1 LAST PART_NUMBER CS03302JB10
J 0
(-3925 4325);
DISPLAY 0.489362 (-3925 4325);
PAINT SKYBLUE (-3925 4325);
DISPLAY INVISIBLE (-3925 4325);
FORCEADD OFFPAGE..1
(-6800 4325);
FORCEPROP 2 LAST $XR1 77 
J 0
(-7141 4325);
DISPLAY 0.638298 (-7141 4325);
PAINT MONO (-7141 4325);
FORCEPROP 2 LAST $XR0 29 
J 0
(-7051 4325);
DISPLAY 0.638298 (-7051 4325);
PAINT MONO (-7051 4325);
FORCEPROP 2 LAST CDS_LIB standard
J 0
(-6800 4325);
DISPLAY INVISIBLE (-6800 4325);
FORCEPROP 1 LAST OFFPAGE TRUE
J 0
(-6470 4195);
PAINT GREEN (-6470 4195);
DISPLAY INVISIBLE (-6470 4195);
FORCEPROP 1 LAST COMMENT_BODY TRUE
J 0
(-6670 4225);
DISPLAY 1.106383 (-6670 4225);
PAINT PEACH (-6670 4225);
DISPLAY INVISIBLE (-6670 4225);
FORCEPROP 2 LAST PATH I232
J 0
(-7050 4375);
DISPLAY 0.680851 (-7050 4375);
DISPLAY INVISIBLE (-7050 4375);
FORCEADD OFFPAGE..1
(-6800 4275);
FORCEPROP 2 LAST $XR1 76 
J 0
(-7141 4275);
DISPLAY 0.638298 (-7141 4275);
PAINT MONO (-7141 4275);
FORCEPROP 2 LAST $XR0 29 
J 0
(-7051 4275);
DISPLAY 0.638298 (-7051 4275);
PAINT MONO (-7051 4275);
FORCEPROP 2 LAST CDS_LIB standard
J 0
(-6800 4275);
DISPLAY INVISIBLE (-6800 4275);
FORCEPROP 1 LAST OFFPAGE TRUE
J 0
(-6470 4145);
PAINT GREEN (-6470 4145);
DISPLAY INVISIBLE (-6470 4145);
FORCEPROP 1 LAST COMMENT_BODY TRUE
J 0
(-6670 4175);
DISPLAY 1.106383 (-6670 4175);
PAINT PEACH (-6670 4175);
DISPLAY INVISIBLE (-6670 4175);
FORCEPROP 2 LAST PATH I233
J 0
(-7050 4325);
DISPLAY 0.680851 (-7050 4325);
DISPLAY INVISIBLE (-7050 4325);
FORCEADD Q_RES..1
(-6800 2375);
FORCEPROP 1 LAST LOCATION R8005
J 0
(-7075 2375);
DISPLAY 0.787234 (-7075 2375);
FORCEPROP 2 LAST SEC 1
J 0
(-6850 2575);
DISPLAY 0.680851 (-6850 2575);
PAINT MONO (-6850 2575);
DISPLAY INVISIBLE (-6850 2575);
FORCEPROP 1 LASTPIN (-6900 2375) $PN 1
J 0
(-6888 2387);
DISPLAY 0.787234 (-6888 2387);
PAINT MONO (-6888 2387);
FORCEPROP 1 LASTPIN (-6700 2375) $PN 2
J 0
(-6738 2387);
DISPLAY 0.787234 (-6738 2387);
PAINT MONO (-6738 2387);
FORCEPROP 1 LAST MATERIAL CHIP
J 0
(-6775 2450);
DISPLAY 0.787234 (-6775 2450);
FORCEPROP 1 LAST VALUE 33
J 2
(-6575 2375);
DISPLAY 0.638298 (-6575 2375);
FORCEPROP 1 LAST PACK_TYPE 0402LF
J 0
(-6775 2500);
DISPLAY 0.787234 (-6775 2500);
FORCEPROP 1 LAST WATTAGE 1/16W
J 2
(-6800 2500);
DISPLAY 0.787234 (-6800 2500);
FORCEPROP 1 LAST TOLERANCE 5%
J 0
(-6900 2450);
DISPLAY 0.787234 (-6900 2450);
FORCEPROP 2 LAST SEC_TYPE 0402LF
J 0
(-6850 2575);
DISPLAY 0.680851 (-6850 2575);
DISPLAY INVISIBLE (-6850 2575);
FORCEPROP 2 LAST CDS_LIB pure_quanta
J 0
(-6800 2375);
DISPLAY INVISIBLE (-6800 2375);
FORCEPROP 1 LAST PATH I234
J 0
(-6850 2525);
DISPLAY 0.978723 (-6850 2525);
PAINT WHITE (-6850 2525);
DISPLAY INVISIBLE (-6850 2525);
FORCEPROP 1 LAST PART_NUMBER CS03302JB10
J 0
(-6975 2550);
DISPLAY 0.787234 (-6975 2550);
DISPLAY INVISIBLE (-6975 2550);
FORCEADD OFFPAGE..3
R 2
(-7875 2375);
FORCEPROP 2 LAST $XR1 77 
J 0
(-8214 2375);
DISPLAY 0.638298 (-8214 2375);
PAINT MONO (-8214 2375);
FORCEPROP 2 LAST $XR0 29 
J 0
(-8124 2375);
DISPLAY 0.638298 (-8124 2375);
PAINT MONO (-8124 2375);
FORCEPROP 2 LAST CDS_LIB standard
J 0
(-7875 2375);
DISPLAY INVISIBLE (-7875 2375);
FORCEPROP 1 LAST OFFPAGE TRUE
J 2
(-8200 2250);
DISPLAY 0.872340 (-8200 2250);
PAINT GREEN (-8200 2250);
DISPLAY INVISIBLE (-8200 2250);
FORCEPROP 1 LAST COMMENT_BODY TRUE
J 2
(-7825 2275);
DISPLAY 0.872340 (-7825 2275);
PAINT PEACH (-7825 2275);
DISPLAY INVISIBLE (-7825 2275);
FORCEPROP 2 LAST PATH I235
J 0
(-8150 2425);
DISPLAY 0.680851 (-8150 2425);
DISPLAY INVISIBLE (-8150 2425);
FORCEADD OFFPAGE..3
R 2
(-7875 2325);
FORCEPROP 2 LAST $XR1 77 
J 0
(-8214 2325);
DISPLAY 0.638298 (-8214 2325);
PAINT MONO (-8214 2325);
FORCEPROP 2 LAST $XR0 29 
J 0
(-8124 2325);
DISPLAY 0.638298 (-8124 2325);
PAINT MONO (-8124 2325);
FORCEPROP 2 LAST CDS_LIB standard
J 0
(-7875 2325);
DISPLAY INVISIBLE (-7875 2325);
FORCEPROP 1 LAST OFFPAGE TRUE
J 2
(-8200 2200);
DISPLAY 0.872340 (-8200 2200);
PAINT GREEN (-8200 2200);
DISPLAY INVISIBLE (-8200 2200);
FORCEPROP 1 LAST COMMENT_BODY TRUE
J 2
(-7825 2225);
DISPLAY 0.872340 (-7825 2225);
PAINT PEACH (-7825 2225);
DISPLAY INVISIBLE (-7825 2225);
FORCEPROP 2 LAST PATH I236
J 0
(-8150 2375);
DISPLAY 0.680851 (-8150 2375);
DISPLAY INVISIBLE (-8150 2375);
FORCEADD OFFPAGE..3
R 2
(-7875 2275);
FORCEPROP 2 LAST $XR1 77 
J 0
(-8214 2275);
DISPLAY 0.638298 (-8214 2275);
PAINT MONO (-8214 2275);
FORCEPROP 2 LAST $XR0 29 
J 0
(-8124 2275);
DISPLAY 0.638298 (-8124 2275);
PAINT MONO (-8124 2275);
FORCEPROP 2 LAST CDS_LIB standard
J 2
(-7875 2275);
DISPLAY INVISIBLE (-7875 2275);
FORCEPROP 1 LAST OFFPAGE TRUE
J 2
(-8200 2150);
DISPLAY 0.872340 (-8200 2150);
PAINT GREEN (-8200 2150);
DISPLAY INVISIBLE (-8200 2150);
FORCEPROP 1 LAST COMMENT_BODY TRUE
J 2
(-7825 2175);
DISPLAY 0.872340 (-7825 2175);
PAINT PEACH (-7825 2175);
DISPLAY INVISIBLE (-7825 2175);
FORCEPROP 2 LAST PATH I237
J 0
(-8150 2325);
DISPLAY 0.680851 (-8150 2325);
DISPLAY INVISIBLE (-8150 2325);
FORCEADD OFFPAGE..3
R 2
(-7875 2225);
FORCEPROP 2 LAST $XR1 77 
J 0
(-8214 2225);
DISPLAY 0.638298 (-8214 2225);
PAINT MONO (-8214 2225);
FORCEPROP 2 LAST $XR0 29 
J 0
(-8124 2225);
DISPLAY 0.638298 (-8124 2225);
PAINT MONO (-8124 2225);
FORCEPROP 2 LAST CDS_LIB standard
J 2
(-7875 2225);
DISPLAY INVISIBLE (-7875 2225);
FORCEPROP 1 LAST OFFPAGE TRUE
J 2
(-8200 2100);
DISPLAY 0.872340 (-8200 2100);
PAINT GREEN (-8200 2100);
DISPLAY INVISIBLE (-8200 2100);
FORCEPROP 1 LAST COMMENT_BODY TRUE
J 2
(-7825 2125);
DISPLAY 0.872340 (-7825 2125);
PAINT PEACH (-7825 2125);
DISPLAY INVISIBLE (-7825 2125);
FORCEPROP 2 LAST PATH I238
J 0
(-8150 2275);
DISPLAY 0.680851 (-8150 2275);
DISPLAY INVISIBLE (-8150 2275);
FORCEADD Q_RES..1
(-6800 2325);
FORCEPROP 1 LAST LOCATION R8006
J 0
(-7075 2325);
DISPLAY 0.787234 (-7075 2325);
FORCEPROP 2 LAST SEC 1
J 0
(-6850 2525);
DISPLAY 0.680851 (-6850 2525);
PAINT MONO (-6850 2525);
DISPLAY INVISIBLE (-6850 2525);
FORCEPROP 1 LASTPIN (-6900 2325) $PN 1
J 0
(-6888 2337);
DISPLAY 0.787234 (-6888 2337);
PAINT MONO (-6888 2337);
FORCEPROP 1 LASTPIN (-6700 2325) $PN 2
J 0
(-6738 2337);
DISPLAY 0.787234 (-6738 2337);
PAINT MONO (-6738 2337);
FORCEPROP 1 LAST VALUE 33
J 2
(-6575 2325);
DISPLAY 0.638298 (-6575 2325);
FORCEPROP 1 LAST PACK_TYPE 0402LF
J 0
(-6775 2450);
DISPLAY 0.787234 (-6775 2450);
DISPLAY INVISIBLE (-6775 2450);
FORCEPROP 2 LAST SEC_TYPE 0402LF
J 0
(-6850 2525);
DISPLAY 0.680851 (-6850 2525);
DISPLAY INVISIBLE (-6850 2525);
FORCEPROP 1 LAST WATTAGE 1/16W
J 2
(-6800 2450);
DISPLAY 0.787234 (-6800 2450);
DISPLAY INVISIBLE (-6800 2450);
FORCEPROP 1 LAST MATERIAL CHIP
J 0
(-6775 2400);
DISPLAY 0.787234 (-6775 2400);
DISPLAY INVISIBLE (-6775 2400);
FORCEPROP 1 LAST TOLERANCE 5%
J 0
(-6900 2400);
DISPLAY 0.787234 (-6900 2400);
DISPLAY INVISIBLE (-6900 2400);
FORCEPROP 2 LAST CDS_LIB pure_quanta
J 0
(-6800 2325);
DISPLAY INVISIBLE (-6800 2325);
FORCEPROP 1 LAST PATH I239
J 0
(-6850 2475);
DISPLAY 0.978723 (-6850 2475);
PAINT WHITE (-6850 2475);
DISPLAY INVISIBLE (-6850 2475);
FORCEPROP 1 LAST PART_NUMBER CS03302JB10
J 0
(-6975 2500);
DISPLAY 0.787234 (-6975 2500);
DISPLAY INVISIBLE (-6975 2500);
FORCEADD Q_RES..1
(-6800 2275);
FORCEPROP 1 LAST LOCATION R8007
J 0
(-7075 2275);
DISPLAY 0.787234 (-7075 2275);
FORCEPROP 2 LAST SEC 1
J 0
(-6850 2475);
DISPLAY 0.680851 (-6850 2475);
PAINT MONO (-6850 2475);
DISPLAY INVISIBLE (-6850 2475);
FORCEPROP 1 LASTPIN (-6900 2275) $PN 1
J 0
(-6888 2287);
DISPLAY 0.787234 (-6888 2287);
PAINT MONO (-6888 2287);
FORCEPROP 1 LASTPIN (-6700 2275) $PN 2
J 0
(-6738 2287);
DISPLAY 0.787234 (-6738 2287);
PAINT MONO (-6738 2287);
FORCEPROP 1 LAST VALUE 33
J 2
(-6575 2275);
DISPLAY 0.638298 (-6575 2275);
FORCEPROP 1 LAST WATTAGE 1/16W
J 2
(-6800 2400);
DISPLAY 0.787234 (-6800 2400);
DISPLAY INVISIBLE (-6800 2400);
FORCEPROP 1 LAST MATERIAL CHIP
J 0
(-6775 2350);
DISPLAY 0.787234 (-6775 2350);
DISPLAY INVISIBLE (-6775 2350);
FORCEPROP 1 LAST TOLERANCE 5%
J 0
(-6900 2350);
DISPLAY 0.787234 (-6900 2350);
DISPLAY INVISIBLE (-6900 2350);
FORCEPROP 2 LAST CDS_LIB pure_quanta
J 0
(-6800 2275);
DISPLAY INVISIBLE (-6800 2275);
FORCEPROP 2 LAST SEC_TYPE 0402LF
J 0
(-6850 2475);
DISPLAY 0.680851 (-6850 2475);
DISPLAY INVISIBLE (-6850 2475);
FORCEPROP 1 LAST PACK_TYPE 0402LF
J 0
(-6775 2400);
DISPLAY 0.787234 (-6775 2400);
DISPLAY INVISIBLE (-6775 2400);
FORCEPROP 1 LAST PATH I240
J 0
(-6850 2425);
DISPLAY 0.978723 (-6850 2425);
PAINT WHITE (-6850 2425);
DISPLAY INVISIBLE (-6850 2425);
FORCEPROP 1 LAST PART_NUMBER CS03302JB10
J 0
(-6975 2450);
DISPLAY 0.787234 (-6975 2450);
DISPLAY INVISIBLE (-6975 2450);
FORCEADD Q_RES..1
(-6800 2225);
FORCEPROP 1 LAST LOCATION R8008
J 0
(-7075 2225);
DISPLAY 0.787234 (-7075 2225);
FORCEPROP 2 LAST SEC 1
J 0
(-6850 2425);
DISPLAY 0.680851 (-6850 2425);
PAINT MONO (-6850 2425);
DISPLAY INVISIBLE (-6850 2425);
FORCEPROP 1 LASTPIN (-6900 2225) $PN 1
J 0
(-6888 2237);
DISPLAY 0.787234 (-6888 2237);
PAINT MONO (-6888 2237);
FORCEPROP 1 LASTPIN (-6700 2225) $PN 2
J 0
(-6738 2237);
DISPLAY 0.787234 (-6738 2237);
PAINT MONO (-6738 2237);
FORCEPROP 1 LAST VALUE 33
J 2
(-6575 2225);
DISPLAY 0.638298 (-6575 2225);
FORCEPROP 1 LAST WATTAGE 1/16W
J 2
(-6800 2350);
DISPLAY 0.787234 (-6800 2350);
DISPLAY INVISIBLE (-6800 2350);
FORCEPROP 1 LAST MATERIAL CHIP
J 0
(-6775 2300);
DISPLAY 0.787234 (-6775 2300);
DISPLAY INVISIBLE (-6775 2300);
FORCEPROP 1 LAST TOLERANCE 5%
J 0
(-6900 2300);
DISPLAY 0.787234 (-6900 2300);
DISPLAY INVISIBLE (-6900 2300);
FORCEPROP 2 LAST CDS_LIB pure_quanta
J 0
(-6800 2225);
DISPLAY INVISIBLE (-6800 2225);
FORCEPROP 2 LAST SEC_TYPE 0402LF
J 0
(-6850 2425);
DISPLAY 0.680851 (-6850 2425);
DISPLAY INVISIBLE (-6850 2425);
FORCEPROP 1 LAST PACK_TYPE 0402LF
J 0
(-6775 2350);
DISPLAY 0.787234 (-6775 2350);
DISPLAY INVISIBLE (-6775 2350);
FORCEPROP 1 LAST PATH I241
J 0
(-6850 2375);
DISPLAY 0.978723 (-6850 2375);
PAINT WHITE (-6850 2375);
DISPLAY INVISIBLE (-6850 2375);
FORCEPROP 1 LAST PART_NUMBER CS03302JB10
J 0
(-6975 2400);
DISPLAY 0.787234 (-6975 2400);
DISPLAY INVISIBLE (-6975 2400);
FORCEADD Q_RES..1
(-3950 4175);
FORCEPROP 1 LAST LOCATION R608
J 0
(-3850 4175);
DISPLAY 0.489362 (-3850 4175);
PAINT SKYBLUE (-3850 4175);
FORCEPROP 0 LAST $SEC 1
J 0
(-3850 4200);
DISPLAY 0.680851 (-3850 4200);
PAINT MONO (-3850 4200);
DISPLAY INVISIBLE (-3850 4200);
FORCEPROP 0 LAST CDS_SEC 1
J 0
(-3850 4200);
DISPLAY 0.680851 (-3850 4200);
DISPLAY INVISIBLE (-3850 4200);
FORCEPROP 1 LASTPIN (-4050 4175) $PN 1
J 0
(-4038 4187);
DISPLAY 0.787234 (-4038 4187);
PAINT MONO (-4038 4187);
FORCEPROP 1 LASTPIN (-3850 4175) $PN 2
J 0
(-3888 4187);
DISPLAY 0.787234 (-3888 4187);
PAINT MONO (-3888 4187);
FORCEPROP 1 LAST VALUE 33
J 2
(-4050 4175);
DISPLAY 0.489362 (-4050 4175);
PAINT SKYBLUE (-4050 4175);
FORCEPROP 2 LAST CDS_LIB pure_quanta
J 0
(-3950 4175);
DISPLAY INVISIBLE (-3950 4175);
FORCEPROP 1 LAST WATTAGE 1/16W
J 2
(-3550 4100);
DISPLAY 0.489362 (-3550 4100);
PAINT SKYBLUE (-3550 4100);
DISPLAY INVISIBLE (-3550 4100);
FORCEPROP 1 LAST MATERIAL CHIP
J 0
(-3525 4100);
DISPLAY 0.489362 (-3525 4100);
PAINT SKYBLUE (-3525 4100);
DISPLAY INVISIBLE (-3525 4100);
FORCEPROP 1 LAST TOLERANCE 5%
J 0
(-3975 4100);
DISPLAY 0.489362 (-3975 4100);
PAINT SKYBLUE (-3975 4100);
DISPLAY INVISIBLE (-3975 4100);
FORCEPROP 1 LAST PACK_TYPE 0402LF
J 0
(-3900 4100);
DISPLAY 0.489362 (-3900 4100);
PAINT SKYBLUE (-3900 4100);
DISPLAY INVISIBLE (-3900 4100);
FORCEPROP 1 LAST PATH I242
J 0
(-4000 4325);
DISPLAY 0.978723 (-4000 4325);
PAINT WHITE (-4000 4325);
DISPLAY INVISIBLE (-4000 4325);
FORCEPROP 1 LAST PART_NUMBER CS03302JB10
J 0
(-3925 4225);
DISPLAY 0.489362 (-3925 4225);
PAINT SKYBLUE (-3925 4225);
DISPLAY INVISIBLE (-3925 4225);
FORCEADD UNIVERSAL_POWER..1
(-4875 5000);
FORCEPROP 3 LASTPIN (-4875 4950) SIG_NAME P3V3_AUX\g
J 0
(-4865 4960);
DISPLAY 0.659574 (-4865 4960);
PAINT MONO (-4865 4960);
DISPLAY INVISIBLE (-4865 4960);
FORCEPROP 1 LAST HDL_POWER P3V3_AUX
J 1
(-4875 5050);
DISPLAY 0.489362 (-4875 5050);
PAINT GREEN (-4875 5050);
FORCEPROP 2 LAST CDS_LIB pure_quanta_power
J 0
(-4875 5000);
DISPLAY INVISIBLE (-4875 5000);
FORCEPROP 1 LAST PATH I49
J 0
(-4825 5025);
DISPLAY 0.872340 (-4825 5025);
PAINT AQUA (-4825 5025);
DISPLAY INVISIBLE (-4825 5025);
FORCEADD Q_CAP..1
(-4750 4750);
FORCEPROP 1 LAST LOCATION C1104
J 0
(-4700 4850);
DISPLAY 0.489362 (-4700 4850);
PAINT SKYBLUE (-4700 4850);
FORCEPROP 0 LAST $SEC 1
J 0
(-4700 4875);
DISPLAY 0.680851 (-4700 4875);
PAINT MONO (-4700 4875);
DISPLAY INVISIBLE (-4700 4875);
FORCEPROP 0 LAST CDS_SEC 1
J 0
(-4700 4875);
DISPLAY 1.021277 (-4700 4875);
DISPLAY INVISIBLE (-4700 4875);
FORCEPROP 1 LASTPIN (-4750 4850) $PN 1
J 0
(-4740 4830);
DISPLAY 0.489362 (-4740 4830);
PAINT MONO (-4740 4830);
FORCEPROP 1 LASTPIN (-4750 4650) $PN 2
J 0
(-4740 4630);
DISPLAY 0.489362 (-4740 4630);
PAINT MONO (-4740 4630);
FORCEPROP 1 LAST PACK_TYPE 0402
J 0
(-4700 4675);
DISPLAY 0.489362 (-4700 4675);
PAINT SKYBLUE (-4700 4675);
FORCEPROP 1 LAST VALUE 0.1UF
J 0
(-4700 4800);
DISPLAY 0.489362 (-4700 4800);
PAINT SKYBLUE (-4700 4800);
FORCEPROP 1 LAST MATERIAL X7R
J 0
(-4700 4725);
DISPLAY 0.489362 (-4700 4725);
PAINT SKYBLUE (-4700 4725);
FORCEPROP 1 LAST VOLTAGE 25V
J 0
(-4700 4775);
DISPLAY 0.489362 (-4700 4775);
PAINT SKYBLUE (-4700 4775);
FORCEPROP 1 LAST TOLERANCE 10%
J 0
(-4700 4750);
DISPLAY 0.489362 (-4700 4750);
PAINT SKYBLUE (-4700 4750);
FORCEPROP 2 LAST CDS_LIB pure_quanta
J 2
(-4750 4750);
DISPLAY INVISIBLE (-4750 4750);
FORCEPROP 1 LAST PATH I50
J 0
(-4700 4900);
DISPLAY 0.978723 (-4700 4900);
PAINT WHITE (-4700 4900);
DISPLAY INVISIBLE (-4700 4900);
FORCEPROP 1 LAST PART_NUMBER CH4104K1B00
J 0
(-4700 4700);
DISPLAY 0.489362 (-4700 4700);
PAINT SKYBLUE (-4700 4700);
DISPLAY INVISIBLE (-4700 4700);
FORCEADD UNIVERSAL_GND..1
R 2
(-4750 4550);
FORCEPROP 3 LASTPIN (-4750 4600) SIG_NAME GND\g
J 0
(-4740 4610);
DISPLAY 0.659574 (-4740 4610);
PAINT MONO (-4740 4610);
DISPLAY INVISIBLE (-4740 4610);
FORCEPROP 2 LAST CDS_LIB pure_quanta_power
J 2
(-4750 4550);
DISPLAY INVISIBLE (-4750 4550);
FORCEPROP 1 LAST HDL_POWER GND
J 1
(-4775 4475);
DISPLAY 0.872340 (-4775 4475);
PAINT GREEN (-4775 4475);
DISPLAY INVISIBLE (-4775 4475);
FORCEPROP 1 LAST PATH I51
J 2
(-4825 4550);
DISPLAY 0.872340 (-4825 4550);
PAINT AQUA (-4825 4550);
DISPLAY INVISIBLE (-4825 4550);
FORCEADD UNIVERSAL_POWER..1
(-5975 4975);
FORCEPROP 3 LASTPIN (-5975 4925) SIG_NAME PVDD18_S5_P0\g
J 0
(-5965 4935);
DISPLAY 0.659574 (-5965 4935);
PAINT MONO (-5965 4935);
DISPLAY INVISIBLE (-5965 4935);
FORCEPROP 1 LAST HDL_POWER PVDD18_S5_P0
J 1
(-5975 5025);
DISPLAY 0.489362 (-5975 5025);
PAINT GREEN (-5975 5025);
FORCEPROP 2 LAST CDS_LIB pure_quanta_power
J 0
(-5975 4975);
DISPLAY INVISIBLE (-5975 4975);
FORCEPROP 1 LAST PATH I52
J 0
(-5925 5000);
DISPLAY 0.872340 (-5925 5000);
PAINT AQUA (-5925 5000);
DISPLAY INVISIBLE (-5925 5000);
FORCEADD Q_CAP..1
R 2
(-6100 4750);
FORCEPROP 1 LAST LOCATION C1102
J 2
(-6150 4825);
DISPLAY 0.489362 (-6150 4825);
PAINT SKYBLUE (-6150 4825);
FORCEPROP 2 LAST $SEC 1
J 0
(-6150 4950);
DISPLAY 0.680851 (-6150 4950);
PAINT MONO (-6150 4950);
DISPLAY INVISIBLE (-6150 4950);
FORCEPROP 2 LAST CDS_SEC 1
J 0
(-6150 4950);
DISPLAY 1.021277 (-6150 4950);
DISPLAY INVISIBLE (-6150 4950);
FORCEPROP 1 LASTPIN (-6100 4850) $PN 1
J 2
(-6110 4830);
DISPLAY 0.489362 (-6110 4830);
FORCEPROP 1 LASTPIN (-6100 4650) $PN 2
J 2
(-6110 4630);
DISPLAY 0.489362 (-6110 4630);
FORCEPROP 1 LAST TOLERANCE 10%
J 2
(-6150 4750);
DISPLAY 0.489362 (-6150 4750);
PAINT SKYBLUE (-6150 4750);
FORCEPROP 1 LAST VOLTAGE 25V
J 2
(-6150 4775);
DISPLAY 0.489362 (-6150 4775);
PAINT SKYBLUE (-6150 4775);
FORCEPROP 1 LAST VALUE 0.1UF
J 2
(-6150 4800);
DISPLAY 0.489362 (-6150 4800);
PAINT SKYBLUE (-6150 4800);
FORCEPROP 1 LAST MATERIAL X7R
J 2
(-6150 4725);
DISPLAY 0.489362 (-6150 4725);
PAINT SKYBLUE (-6150 4725);
FORCEPROP 1 LAST PACK_TYPE 0402
J 2
(-6150 4675);
DISPLAY 0.489362 (-6150 4675);
PAINT SKYBLUE (-6150 4675);
FORCEPROP 2 LAST CDS_LIB pure_quanta
J 0
(-6100 4750);
PAINT MONO (-6100 4750);
DISPLAY INVISIBLE (-6100 4750);
FORCEPROP 1 LAST PATH I53
J 2
(-6150 4900);
DISPLAY 0.978723 (-6150 4900);
PAINT WHITE (-6150 4900);
DISPLAY INVISIBLE (-6150 4900);
FORCEPROP 1 LAST PART_NUMBER CH4104K1B00
J 2
(-6150 4700);
DISPLAY 0.489362 (-6150 4700);
PAINT SKYBLUE (-6150 4700);
DISPLAY INVISIBLE (-6150 4700);
FORCEADD UNIVERSAL_GND..1
(-6100 4550);
FORCEPROP 3 LASTPIN (-6100 4600) SIG_NAME GND\g
J 0
(-6090 4610);
DISPLAY 0.659574 (-6090 4610);
PAINT MONO (-6090 4610);
DISPLAY INVISIBLE (-6090 4610);
FORCEPROP 2 LAST CDS_LIB pure_quanta_power
J 0
(-6100 4550);
PAINT MONO (-6100 4550);
DISPLAY INVISIBLE (-6100 4550);
FORCEPROP 1 LAST HDL_POWER GND
J 1
(-6075 4475);
DISPLAY 0.872340 (-6075 4475);
PAINT GREEN (-6075 4475);
DISPLAY INVISIBLE (-6075 4475);
FORCEPROP 1 LAST PATH I54
J 0
(-6025 4550);
DISPLAY 0.872340 (-6025 4550);
PAINT AQUA (-6025 4550);
DISPLAY INVISIBLE (-6025 4550);
FORCEADD UNIVERSAL_GND..1
R 2
(-4775 3550);
FORCEPROP 3 LASTPIN (-4775 3600) SIG_NAME GND\g
J 0
(-4765 3610);
DISPLAY 0.659574 (-4765 3610);
PAINT MONO (-4765 3610);
DISPLAY INVISIBLE (-4765 3610);
FORCEPROP 2 LAST CDS_LIB pure_quanta_power
J 0
(-4775 3550);
DISPLAY INVISIBLE (-4775 3550);
FORCEPROP 1 LAST HDL_POWER GND
J 1
(-4800 3475);
DISPLAY 0.702128 (-4800 3475);
PAINT GREEN (-4800 3475);
DISPLAY INVISIBLE (-4800 3475);
FORCEPROP 1 LAST PATH I56
J 2
(-4850 3550);
DISPLAY 0.872340 (-4850 3550);
PAINT AQUA (-4850 3550);
DISPLAY INVISIBLE (-4850 3550);
FORCEADD UNIVERSAL_POWER..1
(-4850 2900);
FORCEPROP 3 LASTPIN (-4850 2850) SIG_NAME P3V3_AUX\g
J 0
(-4840 2860);
DISPLAY 0.659574 (-4840 2860);
PAINT MONO (-4840 2860);
DISPLAY INVISIBLE (-4840 2860);
FORCEPROP 1 LAST HDL_POWER P3V3_AUX
J 1
(-4850 2950);
DISPLAY 0.489362 (-4850 2950);
PAINT GREEN (-4850 2950);
FORCEPROP 2 LAST CDS_LIB pure_quanta_power
J 0
(-4850 2900);
DISPLAY INVISIBLE (-4850 2900);
FORCEPROP 1 LAST PATH I57
J 0
(-4800 2925);
DISPLAY 0.872340 (-4800 2925);
PAINT AQUA (-4800 2925);
DISPLAY INVISIBLE (-4800 2925);
FORCEADD Q_CAP..1
(-4725 2650);
FORCEPROP 1 LAST LOCATION C1105
J 0
(-4675 2750);
DISPLAY 0.489362 (-4675 2750);
PAINT SKYBLUE (-4675 2750);
FORCEPROP 0 LAST $SEC 1
J 0
(-4675 2775);
DISPLAY 0.680851 (-4675 2775);
PAINT MONO (-4675 2775);
DISPLAY INVISIBLE (-4675 2775);
FORCEPROP 0 LAST CDS_SEC 1
J 0
(-4675 2775);
DISPLAY 1.021277 (-4675 2775);
DISPLAY INVISIBLE (-4675 2775);
FORCEPROP 1 LASTPIN (-4725 2750) $PN 1
J 0
(-4715 2730);
DISPLAY 0.489362 (-4715 2730);
PAINT MONO (-4715 2730);
FORCEPROP 1 LASTPIN (-4725 2550) $PN 2
J 0
(-4715 2530);
DISPLAY 0.489362 (-4715 2530);
PAINT MONO (-4715 2530);
FORCEPROP 1 LAST VOLTAGE 25V
J 0
(-4675 2675);
DISPLAY 0.489362 (-4675 2675);
PAINT SKYBLUE (-4675 2675);
FORCEPROP 1 LAST TOLERANCE 10%
J 0
(-4675 2650);
DISPLAY 0.489362 (-4675 2650);
PAINT SKYBLUE (-4675 2650);
FORCEPROP 1 LAST VALUE 0.1UF
J 0
(-4675 2700);
DISPLAY 0.489362 (-4675 2700);
PAINT SKYBLUE (-4675 2700);
FORCEPROP 1 LAST MATERIAL X7R
J 0
(-4675 2625);
DISPLAY 0.489362 (-4675 2625);
PAINT SKYBLUE (-4675 2625);
FORCEPROP 1 LAST PACK_TYPE 0402
J 0
(-4675 2575);
DISPLAY 0.489362 (-4675 2575);
PAINT SKYBLUE (-4675 2575);
FORCEPROP 2 LAST CDS_LIB pure_quanta
J 0
(-4725 2650);
DISPLAY INVISIBLE (-4725 2650);
FORCEPROP 1 LAST PATH I59
J 0
(-4675 2800);
DISPLAY 0.978723 (-4675 2800);
PAINT WHITE (-4675 2800);
DISPLAY INVISIBLE (-4675 2800);
FORCEPROP 1 LAST PART_NUMBER CH4104K1B00
J 0
(-4675 2600);
DISPLAY 0.489362 (-4675 2600);
PAINT SKYBLUE (-4675 2600);
DISPLAY INVISIBLE (-4675 2600);
FORCEADD UNIVERSAL_GND..1
R 2
(-4825 1700);
FORCEPROP 3 LASTPIN (-4825 1750) SIG_NAME GND\g
J 0
(-4815 1760);
DISPLAY 0.659574 (-4815 1760);
PAINT MONO (-4815 1760);
DISPLAY INVISIBLE (-4815 1760);
FORCEPROP 2 LAST CDS_LIB pure_quanta_power
J 0
(-4825 1700);
DISPLAY INVISIBLE (-4825 1700);
FORCEPROP 1 LAST HDL_POWER GND
J 1
(-4850 1625);
DISPLAY 0.702128 (-4850 1625);
PAINT GREEN (-4850 1625);
DISPLAY INVISIBLE (-4850 1625);
FORCEPROP 1 LAST PATH I62
J 2
(-4900 1700);
DISPLAY 0.872340 (-4900 1700);
PAINT AQUA (-4900 1700);
DISPLAY INVISIBLE (-4900 1700);
FORCEADD SN74AVC4T774PWR..1
(-5425 4175);
FORCEPROP 1 LAST LOCATION U53
J 0
(-5675 4725);
DISPLAY 0.574468 (-5675 4725);
PAINT SKYBLUE (-5675 4725);
FORCEPROP 0 LAST $SEC 1
J 0
(-5675 4875);
DISPLAY 0.680851 (-5675 4875);
PAINT MONO (-5675 4875);
DISPLAY INVISIBLE (-5675 4875);
FORCEPROP 0 LAST CDS_SEC 1
J 0
(-5650 4725);
DISPLAY 1.021277 (-5650 4725);
DISPLAY INVISIBLE (-5650 4725);
FORCEPROP 0 LASTPIN (-5825 4325) $PN 3
J 2
(-5835 4335);
DISPLAY 0.680851 (-5835 4335);
PAINT MONO (-5835 4335);
FORCEPROP 0 LASTPIN (-5825 4275) $PN 4
J 2
(-5835 4285);
DISPLAY 0.680851 (-5835 4285);
PAINT MONO (-5835 4285);
FORCEPROP 0 LASTPIN (-5825 4225) $PN 5
J 2
(-5835 4235);
DISPLAY 0.680851 (-5835 4235);
PAINT MONO (-5835 4235);
FORCEPROP 0 LASTPIN (-5825 4175) $PN 6
J 2
(-5835 4185);
DISPLAY 0.680851 (-5835 4185);
PAINT MONO (-5835 4185);
FORCEPROP 0 LASTPIN (-5025 4325) $PN 14
J 0
(-5015 4335);
DISPLAY 0.680851 (-5015 4335);
PAINT MONO (-5015 4335);
FORCEPROP 0 LASTPIN (-5025 4275) $PN 13
J 0
(-5015 4285);
DISPLAY 0.680851 (-5015 4285);
PAINT MONO (-5015 4285);
FORCEPROP 0 LASTPIN (-5025 4225) $PN 12
J 0
(-5015 4235);
DISPLAY 0.680851 (-5015 4235);
PAINT MONO (-5015 4235);
FORCEPROP 0 LASTPIN (-5025 4175) $PN 11
J 0
(-5015 4185);
DISPLAY 0.680851 (-5015 4185);
PAINT MONO (-5015 4185);
FORCEPROP 0 LASTPIN (-5825 4025) $PN 1
J 2
(-5835 4035);
DISPLAY 0.680851 (-5835 4035);
PAINT MONO (-5835 4035);
FORCEPROP 0 LASTPIN (-5825 3975) $PN 2
J 2
(-5835 3985);
DISPLAY 0.680851 (-5835 3985);
PAINT MONO (-5835 3985);
FORCEPROP 0 LASTPIN (-5825 3925) $PN 7
J 2
(-5835 3935);
DISPLAY 0.680851 (-5835 3935);
PAINT MONO (-5835 3935);
FORCEPROP 0 LASTPIN (-5825 3875) $PN 8
J 2
(-5835 3885);
DISPLAY 0.680851 (-5835 3885);
PAINT MONO (-5835 3885);
FORCEPROP 0 LASTPIN (-5025 3775) $PN 10
J 0
(-5015 3785);
DISPLAY 0.680851 (-5015 3785);
PAINT MONO (-5015 3785);
FORCEPROP 0 LASTPIN (-5825 3825) $PN 9
J 2
(-5835 3835);
DISPLAY 0.680851 (-5835 3835);
PAINT MONO (-5835 3835);
FORCEPROP 0 LASTPIN (-5825 4525) $PN 16
J 2
(-5835 4535);
DISPLAY 0.680851 (-5835 4535);
PAINT MONO (-5835 4535);
FORCEPROP 0 LASTPIN (-5025 4525) $PN 15
J 0
(-5015 4535);
DISPLAY 0.680851 (-5015 4535);
PAINT MONO (-5015 4535);
FORCEPROP 2 LAST VALUE SN74AVC4T774PWR
J 0
(-5675 4775);
DISPLAY 0.489362 (-5675 4775);
PAINT SKYBLUE (-5675 4775);
FORCEPROP 1 LAST MATERIAL IC
J 0
(-5675 4650);
DISPLAY 0.468085 (-5675 4650);
PAINT SKYBLUE (-5675 4650);
FORCEPROP 2 LAST PART_TYPE SMLF
J 0
(-5675 4825);
DISPLAY 1.021277 (-5675 4825);
FORCEPROP 1 LAST CDS_LMAN_SYM_OUTLINE -250,450,250,-450
J 0
(-5425 4175);
DISPLAY 0.468085 (-5425 4175);
PAINT GREEN (-5425 4175);
DISPLAY INVISIBLE (-5425 4175);
FORCEPROP 1 LAST NEEDS_NO_SIZE TRUE
J 0
(-5425 4175);
DISPLAY 0.723404 (-5425 4175);
PAINT GREEN (-5425 4175);
DISPLAY INVISIBLE (-5425 4175);
FORCEPROP 2 LAST CDS_LIB pure_quanta
J 0
(-5425 4175);
DISPLAY INVISIBLE (-5425 4175);
FORCEPROP 1 LAST PATH I63
J 0
(-5425 4175);
DISPLAY 0.723404 (-5425 4175);
PAINT GREEN (-5425 4175);
DISPLAY INVISIBLE (-5425 4175);
FORCEPROP 1 LAST PART_NUMBER AL04T774K00
J 0
(-5675 4700);
DISPLAY 0.468085 (-5675 4700);
PAINT SKYBLUE (-5675 4700);
DISPLAY INVISIBLE (-5675 4700);
FORCEADD UNIVERSAL_POWER..1
(-6075 2900);
FORCEPROP 3 LASTPIN (-6075 2850) SIG_NAME PVDD18_S5_P0\g
J 0
(-6065 2860);
DISPLAY 0.659574 (-6065 2860);
PAINT MONO (-6065 2860);
DISPLAY INVISIBLE (-6065 2860);
FORCEPROP 1 LAST HDL_POWER PVDD18_S5_P0
J 1
(-6075 2950);
DISPLAY 0.489362 (-6075 2950);
PAINT GREEN (-6075 2950);
FORCEPROP 2 LAST CDS_LIB pure_quanta_power
J 0
(-6075 2900);
DISPLAY INVISIBLE (-6075 2900);
FORCEPROP 1 LAST PATH I64
J 0
(-6025 2925);
DISPLAY 0.872340 (-6025 2925);
PAINT AQUA (-6025 2925);
DISPLAY INVISIBLE (-6025 2925);
FORCEADD Q_CAP..1
R 2
(-6200 2675);
FORCEPROP 1 LAST LOCATION C1103
J 2
(-6250 2775);
DISPLAY 0.489362 (-6250 2775);
PAINT SKYBLUE (-6250 2775);
FORCEPROP 0 LAST $SEC 1
J 0
(-6250 2800);
DISPLAY 0.680851 (-6250 2800);
PAINT MONO (-6250 2800);
DISPLAY INVISIBLE (-6250 2800);
FORCEPROP 0 LAST CDS_SEC 1
J 0
(-6250 2800);
DISPLAY 1.021277 (-6250 2800);
DISPLAY INVISIBLE (-6250 2800);
FORCEPROP 1 LASTPIN (-6200 2775) $PN 1
J 2
(-6210 2755);
DISPLAY 0.489362 (-6210 2755);
PAINT MONO (-6210 2755);
FORCEPROP 1 LASTPIN (-6200 2575) $PN 2
J 2
(-6210 2555);
DISPLAY 0.489362 (-6210 2555);
PAINT MONO (-6210 2555);
FORCEPROP 1 LAST PACK_TYPE 0402
J 2
(-6250 2600);
DISPLAY 0.489362 (-6250 2600);
PAINT SKYBLUE (-6250 2600);
FORCEPROP 1 LAST VALUE 0.1UF
J 2
(-6250 2725);
DISPLAY 0.489362 (-6250 2725);
PAINT SKYBLUE (-6250 2725);
FORCEPROP 1 LAST MATERIAL X7R
J 2
(-6250 2650);
DISPLAY 0.489362 (-6250 2650);
PAINT SKYBLUE (-6250 2650);
FORCEPROP 1 LAST TOLERANCE 10%
J 2
(-6250 2675);
DISPLAY 0.489362 (-6250 2675);
PAINT SKYBLUE (-6250 2675);
FORCEPROP 1 LAST VOLTAGE 25V
J 2
(-6250 2700);
DISPLAY 0.489362 (-6250 2700);
PAINT SKYBLUE (-6250 2700);
FORCEPROP 2 LAST CDS_LIB pure_quanta
J 0
(-6200 2675);
DISPLAY INVISIBLE (-6200 2675);
FORCEPROP 1 LAST PATH I65
J 2
(-6250 2825);
DISPLAY 0.978723 (-6250 2825);
PAINT WHITE (-6250 2825);
DISPLAY INVISIBLE (-6250 2825);
FORCEPROP 1 LAST PART_NUMBER CH4104K1B00
J 2
(-6250 2625);
DISPLAY 0.489362 (-6250 2625);
PAINT SKYBLUE (-6250 2625);
DISPLAY INVISIBLE (-6250 2625);
FORCEADD PI4ULS3V304AZMAEX..1
(-5550 2275);
FORCEPROP 1 LAST LOCATION U54
J 0
(-5800 2625);
DISPLAY 0.468085 (-5800 2625);
PAINT SKYBLUE (-5800 2625);
FORCEPROP 0 LAST $SEC 1
J 0
(-5800 2775);
DISPLAY 0.680851 (-5800 2775);
PAINT MONO (-5800 2775);
DISPLAY INVISIBLE (-5800 2775);
FORCEPROP 0 LAST CDS_SEC 1
J 0
(-5775 2825);
DISPLAY 1.021277 (-5775 2825);
DISPLAY INVISIBLE (-5775 2825);
FORCEPROP 0 LASTPIN (-5950 2375) $PN 2
J 2
(-5960 2385);
DISPLAY 0.680851 (-5960 2385);
PAINT MONO (-5960 2385);
FORCEPROP 0 LASTPIN (-5950 2325) $PN 3
J 2
(-5960 2335);
DISPLAY 0.680851 (-5960 2335);
PAINT MONO (-5960 2335);
FORCEPROP 0 LASTPIN (-5950 2275) $PN 4
J 2
(-5960 2285);
DISPLAY 0.680851 (-5960 2285);
PAINT MONO (-5960 2285);
FORCEPROP 0 LASTPIN (-5950 2225) $PN 5
J 2
(-5960 2235);
DISPLAY 0.680851 (-5960 2235);
PAINT MONO (-5960 2235);
FORCEPROP 0 LASTPIN (-5150 2375) $PN 10
J 0
(-5140 2385);
DISPLAY 0.680851 (-5140 2385);
PAINT MONO (-5140 2385);
FORCEPROP 0 LASTPIN (-5150 2325) $PN 9
J 0
(-5140 2335);
DISPLAY 0.680851 (-5140 2335);
PAINT MONO (-5140 2335);
FORCEPROP 0 LASTPIN (-5150 2275) $PN 8
J 0
(-5140 2285);
DISPLAY 0.680851 (-5140 2285);
PAINT MONO (-5140 2285);
FORCEPROP 0 LASTPIN (-5150 2225) $PN 7
J 0
(-5140 2235);
DISPLAY 0.680851 (-5140 2235);
PAINT MONO (-5140 2235);
FORCEPROP 0 LASTPIN (-5950 2125) $PN 12
J 2
(-5960 2135);
DISPLAY 0.680851 (-5960 2135);
PAINT MONO (-5960 2135);
FORCEPROP 0 LASTPIN (-5150 2125) $PN 6
J 0
(-5140 2135);
DISPLAY 0.680851 (-5140 2135);
PAINT MONO (-5140 2135);
FORCEPROP 0 LASTPIN (-5950 2475) $PN 1
J 2
(-5960 2485);
DISPLAY 0.680851 (-5960 2485);
PAINT MONO (-5960 2485);
FORCEPROP 0 LASTPIN (-5150 2475) $PN 11
J 0
(-5140 2485);
DISPLAY 0.680851 (-5140 2485);
PAINT MONO (-5140 2485);
FORCEPROP 2 LAST PART_TYPE SMLF
J 0
(-5800 2725);
DISPLAY 1.021277 (-5800 2725);
FORCEPROP 1 LAST MATERIAL IC
J 0
(-5795 2557);
DISPLAY 0.468085 (-5795 2557);
PAINT SKYBLUE (-5795 2557);
FORCEPROP 2 LAST VALUE PI4ULS3V304AZMAEX
J 0
(-5800 2675);
DISPLAY 0.489362 (-5800 2675);
PAINT SKYBLUE (-5800 2675);
FORCEPROP 1 LAST CDS_LMAN_SYM_OUTLINE -250,250,250,-250
J 0
(-5550 2275);
DISPLAY 0.468085 (-5550 2275);
PAINT GREEN (-5550 2275);
DISPLAY INVISIBLE (-5550 2275);
FORCEPROP 1 LAST NEEDS_NO_SIZE TRUE
J 0
(-5550 2275);
DISPLAY 0.723404 (-5550 2275);
PAINT GREEN (-5550 2275);
DISPLAY INVISIBLE (-5550 2275);
FORCEPROP 2 LAST CDS_LIB pure_quanta
J 0
(-5550 2275);
DISPLAY INVISIBLE (-5550 2275);
FORCEPROP 1 LAST PATH I67
J 0
(-5550 2275);
DISPLAY 0.723404 (-5550 2275);
PAINT GREEN (-5550 2275);
DISPLAY INVISIBLE (-5550 2275);
FORCEPROP 1 LAST PART_NUMBER AL000304005
J 0
(-5800 2600);
DISPLAY 0.468085 (-5800 2600);
PAINT SKYBLUE (-5800 2600);
DISPLAY INVISIBLE (-5800 2600);
FORCEADD UNIVERSAL_POWER..1
R 2
(-2225 5925);
FORCEPROP 3 LASTPIN (-2225 5875) SIG_NAME P3V3_AUX\g
J 0
(-2215 5885);
DISPLAY 0.659574 (-2215 5885);
PAINT MONO (-2215 5885);
DISPLAY INVISIBLE (-2215 5885);
FORCEPROP 1 LAST HDL_POWER P3V3_AUX
J 1
(-2225 5975);
DISPLAY 0.489362 (-2225 5975);
PAINT GREEN (-2225 5975);
FORCEPROP 2 LAST CDS_LIB pure_quanta_power
J 2
(-2225 5925);
DISPLAY INVISIBLE (-2225 5925);
FORCEPROP 1 LAST PATH I96
J 2
(-2275 5950);
DISPLAY 0.872340 (-2275 5950);
PAINT AQUA (-2275 5950);
DISPLAY INVISIBLE (-2275 5950);
FORCEADD Q_RES..2
R 2
(-2050 5625);
FORCEPROP 1 LAST LOCATION R610
J 0
(-2025 5725);
DISPLAY 0.489362 (-2025 5725);
PAINT SKYBLUE (-2025 5725);
FORCEPROP 0 LAST $SEC 1
J 2
(-2100 5775);
DISPLAY 0.680851 (-2100 5775);
PAINT MONO (-2100 5775);
DISPLAY INVISIBLE (-2100 5775);
FORCEPROP 0 LAST CDS_SEC 1
J 2
(-2100 5775);
DISPLAY 1.021277 (-2100 5775);
DISPLAY INVISIBLE (-2100 5775);
FORCEPROP 1 LASTPIN (-2050 5725) $PN 1
J 2
(-2055 5687);
DISPLAY 0.489362 (-2055 5687);
PAINT MONO (-2055 5687);
FORCEPROP 1 LASTPIN (-2050 5525) $PN 2
J 2
(-2055 5535);
DISPLAY 0.489362 (-2055 5535);
PAINT MONO (-2055 5535);
FORCEPROP 1 LAST TOLERANCE 1%
J 0
(-2025 5625);
DISPLAY 0.489362 (-2025 5625);
PAINT SKYBLUE (-2025 5625);
FORCEPROP 1 LAST VALUE 1K
J 0
(-2025 5675);
DISPLAY 0.489362 (-2025 5675);
PAINT SKYBLUE (-2025 5675);
FORCEPROP 1 LAST MATERIAL EMPTY
J 0
(-2025 5575);
DISPLAY 0.489362 (-2025 5575);
PAINT RED (-2025 5575);
FORCEPROP 2 LAST CDS_LIB pure_quanta
J 2
(-2050 5625);
DISPLAY INVISIBLE (-2050 5625);
FORCEPROP 1 LAST WATTAGE 1/16W
J 2
(-2100 5625);
DISPLAY 0.489362 (-2100 5625);
PAINT SKYBLUE (-2100 5625);
DISPLAY INVISIBLE (-2100 5625);
FORCEPROP 1 LAST PACK_TYPE 0402LF
J 2
(-2100 5575);
DISPLAY 0.489362 (-2100 5575);
PAINT SKYBLUE (-2100 5575);
DISPLAY INVISIBLE (-2100 5575);
FORCEPROP 1 LAST PATH I97
J 2
(-2100 5800);
DISPLAY 0.978723 (-2100 5800);
PAINT WHITE (-2100 5800);
DISPLAY INVISIBLE (-2100 5800);
FORCEPROP 1 LAST PART_NUMBER CS21002FB06
J 2
(-2100 5550);
DISPLAY 0.489362 (-2100 5550);
PAINT SKYBLUE (-2100 5550);
DISPLAY INVISIBLE (-2100 5550);
FORCEADD OFFPAGE..2
R 2
(-3125 5400);
FORCEPROP 2 LAST $XR1 150 
J 0
(-3499 5400);
DISPLAY 0.638298 (-3499 5400);
PAINT MONO (-3499 5400);
FORCEPROP 2 LAST $XR0 77 
J 0
(-3379 5400);
DISPLAY 0.638298 (-3379 5400);
PAINT MONO (-3379 5400);
FORCEPROP 2 LAST CDS_LIB standard
J 2
(-3125 5400);
DISPLAY INVISIBLE (-3125 5400);
FORCEPROP 1 LAST OFFPAGE TRUE
J 2
(-3450 5275);
DISPLAY 0.872340 (-3450 5275);
PAINT GREEN (-3450 5275);
DISPLAY INVISIBLE (-3450 5275);
FORCEPROP 1 LAST COMMENT_BODY TRUE
J 2
(-3080 5305);
DISPLAY 0.872340 (-3080 5305);
PAINT PEACH (-3080 5305);
DISPLAY INVISIBLE (-3080 5305);
FORCEPROP 2 LAST PATH I99
J 0
(-3375 5450);
DISPLAY 1.021277 (-3375 5450);
DISPLAY INVISIBLE (-3375 5450);
FORCEADD DNS..2
(-1350 5650);
PAINT RED (-1350 5650);
FORCEPROP 2 LAST CDS_LIB mstr_misc
J 0
(-1350 5650);
DISPLAY INVISIBLE (-1350 5650);
FORCEPROP 1 LAST COMMENT_BODY TRUE
R 1
J 0
(-1275 5425);
DISPLAY 0.872340 (-1275 5425);
PAINT GREEN (-1275 5425);
DISPLAY INVISIBLE (-1275 5425);
FORCEADD DNS..2
(-1525 5650);
PAINT RED (-1525 5650);
FORCEPROP 2 LAST CDS_LIB mstr_misc
J 0
(-1525 5650);
DISPLAY INVISIBLE (-1525 5650);
FORCEPROP 1 LAST COMMENT_BODY TRUE
R 1
J 0
(-1450 5425);
DISPLAY 0.872340 (-1450 5425);
PAINT GREEN (-1450 5425);
DISPLAY INVISIBLE (-1450 5425);
FORCEADD DNS..2
(-1725 5650);
PAINT RED (-1725 5650);
FORCEPROP 2 LAST CDS_LIB mstr_misc
J 0
(-1725 5650);
DISPLAY INVISIBLE (-1725 5650);
FORCEPROP 1 LAST COMMENT_BODY TRUE
R 1
J 0
(-1650 5425);
DISPLAY 0.872340 (-1650 5425);
PAINT GREEN (-1650 5425);
DISPLAY INVISIBLE (-1650 5425);
FORCEADD DNS..2
(-1875 5650);
PAINT RED (-1875 5650);
FORCEPROP 2 LAST CDS_LIB mstr_misc
J 0
(-1875 5650);
DISPLAY INVISIBLE (-1875 5650);
FORCEPROP 1 LAST COMMENT_BODY TRUE
R 1
J 0
(-1800 5425);
DISPLAY 0.872340 (-1800 5425);
PAINT GREEN (-1800 5425);
DISPLAY INVISIBLE (-1800 5425);
FORCEADD QUANTA_TITLE_BLOCK_C..1
(0 0);
FORCEPROP 0 LAST CDS_CON_LAST_MODIFIED Thu Sep 14 16:12:04 2023
J 0
(-1885 15);
DISPLAY INVISIBLE (-1885 15);
FORCEPROP 1 LAST CUSTOM_TXT_CDS <CON_LAST_MODIFIED>
J 0
(-1885 15);
DISPLAY 0.978723 (-1885 15);
FORCEPROP 2 LAST CUSTOM_TXT_CDS <XR_PAGE_TITLE>
J 0
(-7890 5250);
DISPLAY 0.638298 (-7890 5250);
PAINT PINK (-7890 5250);
DISPLAY INVISIBLE (-7890 5250);
FORCEPROP 1 LAST CUSTOM_TXT_CDS <NAME_2>
J 0
(-3175 50);
FORCEPROP 1 LAST CUSTOM_TXT_CDS <NAME_1>
J 0
(-3175 175);
FORCEPROP 1 LAST CUSTOM_TXT_CDS <Q_NUMBER>
J 0
(-1403 103);
DISPLAY 1.212766 (-1403 103);
FORCEPROP 1 LAST CUSTOM_TXT_CDS <Q_PROJ>
J 0
(-2382 102);
DISPLAY 1.212766 (-2382 102);
FORCEPROP 1 LAST CUSTOM_TXT_CDS <Q_REV>
J 0
(-184 103);
DISPLAY 1.212766 (-184 103);
FORCEPROP 1 LAST CUSTOM_TXT_CDS <CON_PAGE_NUM> OF <CON_TOTAL_PAGES>
J 0
(-446 18);
DISPLAY 0.978723 (-446 18);
FORCEPROP 1 LAST Q_TITLE CPU SPI LEVEL SHIFT
J 0
(-9300 50);
DISPLAY 2.446809 (-9300 50);
PAINT GREEN (-9300 50);
FORCEPROP 2 LAST PAGE_BORDER TRUE
J 0
(-7890 5250);
DISPLAY 0.638298 (-7890 5250);
PAINT PINK (-7890 5250);
DISPLAY INVISIBLE (-7890 5250);
FORCEPROP 1 LAST CDS_LMAN_SYM_OUTLINE -9475,6775,100,-125
J 0
(0 0);
DISPLAY 0.468085 (0 0);
PAINT GREEN (0 0);
DISPLAY INVISIBLE (0 0);
FORCEPROP 2 LAST CDS_LIB pure_quanta
J 0
(0 0);
DISPLAY INVISIBLE (0 0);
FORCEPROP 2 LAST CDS_XR_PAGE_TITLE CR-77 : @T6G_MB_LIB.T6G(SCH_1):PAGE77
J 0
(-7890 5250);
DISPLAY 0.638298 (-7890 5250);
PAINT PINK (-7890 5250);
DISPLAY INVISIBLE (-7890 5250);
FORCEPROP 1 LAST Q_DEPT BU9
J 1
(-3763 49);
DISPLAY 1.957447 (-3763 49);
PAINT GREEN (-3763 49);
DISPLAY INVISIBLE (-3763 49);
FORCEPROP 1 LAST COMMENT_BODY TRUE
J 0
(12 -13);
DISPLAY 0.978723 (12 -13);
PAINT GREEN (12 -13);
DISPLAY INVISIBLE (12 -13);
FORCEADD DNS..2
(-9100 5900);
PAINT RED (-9100 5900);
FORCEPROP 2 LAST CDS_LIB mstr_misc
J 0
(-9100 5900);
DISPLAY INVISIBLE (-9100 5900);
FORCEPROP 1 LAST COMMENT_BODY TRUE
R 1
J 0
(-9025 5675);
DISPLAY 0.872340 (-9025 5675);
PAINT GREEN (-9025 5675);
DISPLAY INVISIBLE (-9025 5675);
FORCEADD DNS..2
(-8925 5900);
PAINT RED (-8925 5900);
FORCEPROP 2 LAST CDS_LIB mstr_misc
J 0
(-8925 5900);
DISPLAY INVISIBLE (-8925 5900);
FORCEPROP 1 LAST COMMENT_BODY TRUE
R 1
J 0
(-8850 5675);
DISPLAY 0.872340 (-8850 5675);
PAINT GREEN (-8850 5675);
DISPLAY INVISIBLE (-8850 5675);
FORCEADD DNS..2
(-8750 5900);
PAINT RED (-8750 5900);
FORCEPROP 2 LAST CDS_LIB mstr_misc
J 0
(-8750 5900);
DISPLAY INVISIBLE (-8750 5900);
FORCEPROP 1 LAST COMMENT_BODY TRUE
R 1
J 0
(-8675 5675);
DISPLAY 0.872340 (-8675 5675);
PAINT GREEN (-8675 5675);
DISPLAY INVISIBLE (-8675 5675);
FORCEADD DNS..2
(-8550 5900);
PAINT RED (-8550 5900);
FORCEPROP 2 LAST CDS_LIB mstr_misc
J 0
(-8550 5900);
DISPLAY INVISIBLE (-8550 5900);
FORCEPROP 1 LAST COMMENT_BODY TRUE
R 1
J 0
(-8475 5675);
DISPLAY 0.872340 (-8475 5675);
PAINT GREEN (-8475 5675);
DISPLAY INVISIBLE (-8475 5675);
FORCEADD DNS..2
(-2050 5650);
PAINT RED (-2050 5650);
FORCEPROP 2 LAST CDS_LIB mstr_misc
J 0
(-2050 5650);
DISPLAY INVISIBLE (-2050 5650);
FORCEPROP 1 LAST COMMENT_BODY TRUE
R 1
J 0
(-1975 5425);
DISPLAY 0.872340 (-1975 5425);
PAINT GREEN (-1975 5425);
DISPLAY INVISIBLE (-1975 5425);
FORCEADD DNS..2
(-1000 5625);
PAINT RED (-1000 5625);
FORCEPROP 2 LAST CDS_LIB mstr_misc
J 0
(-1000 5625);
DISPLAY INVISIBLE (-1000 5625);
FORCEPROP 1 LAST COMMENT_BODY TRUE
R 1
J 0
(-925 5400);
DISPLAY 0.872340 (-925 5400);
PAINT GREEN (-925 5400);
DISPLAY INVISIBLE (-925 5400);
WIRE 16 -1 (-6200 2575)(-6200 2550);
WIRE 16 -1 (-4725 2550)(-4725 2500);
WIRE 16 -1 (-4750 4600)(-4750 4650);
WIRE 16 -1 (-6100 4600)(-6100 4650);
WIRE 16 -1 (-5025 3775)(-4775 3775);
WIRE 16 -1 (-4775 3775)(-4775 3600);
WIRE 16 -1 (-5150 2125)(-4825 2125);
WIRE 16 -1 (-4825 2125)(-4825 1750);
WIRE 16 -1 (-5025 4325)(-4050 4325);
FORCEPROP 2 LAST SIG_NAME SPI_CPU0_LVC3_CS0_N
J 0
(-4785 4325);
DISPLAY 0.489362 (-4785 4325);
FORCEPROP 2 LASTPROP $XRERR UNIQUE?
J 0
(-5025 4325);
DISPLAY 0.638298 (-5025 4325);
PAINT MONO (-5025 4325);
DISPLAY INVISIBLE (-5025 4325);
WIRE 16 -1 (-4050 4225)(-5025 4225);
FORCEPROP 2 LAST SIG_NAME SPI_CPU0_LVC3_CS1_N
J 0
(-4785 4225);
DISPLAY 0.489362 (-4785 4225);
FORCEPROP 2 LASTPROP $XRERR UNIQUE?
J 0
(-5025 4225);
DISPLAY 0.638298 (-5025 4225);
PAINT MONO (-5025 4225);
DISPLAY INVISIBLE (-5025 4225);
WIRE 16 -1 (-3050 4325)(-3850 4325);
FORCEPROP 2 LAST SIG_NAME SPI_CPU0_LVC3_SCM_CS0_N
J 0
(-3710 4335);
DISPLAY 0.489362 (-3710 4335);
WIRE 16 -1 (-5025 4275)(-4050 4275);
FORCEPROP 2 LAST SIG_NAME SPI_CPU0_LVC3_CLK
J 0
(-4785 4275);
DISPLAY 0.489362 (-4785 4275);
FORCEPROP 2 LASTPROP $XRERR UNIQUE?
J 0
(-5025 4275);
DISPLAY 0.638298 (-5025 4275);
PAINT MONO (-5025 4275);
DISPLAY INVISIBLE (-5025 4275);
WIRE 16 -1 (-5025 4175)(-4050 4175);
FORCEPROP 2 LAST SIG_NAME SPI_CPU0_LVC3_R_TPM_CS_N
J 0
(-4785 4185);
DISPLAY 0.489362 (-4785 4185);
FORCEPROP 2 LASTPROP $XRERR UNIQUE?
J 0
(-5025 4185);
DISPLAY 0.638298 (-5025 4185);
PAINT MONO (-5025 4185);
DISPLAY INVISIBLE (-5025 4185);
WIRE 16 -1 (-3850 4175)(-3050 4175);
FORCEPROP 2 LAST SIG_NAME SPI_CPU0_LVC3_TPM_CS_N
J 0
(-3700 4185);
DISPLAY 0.489362 (-3700 4185);
WIRE 16 -1 (-3050 4225)(-3850 4225);
FORCEPROP 2 LAST SIG_NAME SPI_CPU0_LVC3_SCM_CS1_N
J 0
(-3710 4235);
DISPLAY 0.489362 (-3710 4235);
WIRE 16 -1 (-3850 4275)(-3050 4275);
FORCEPROP 2 LAST SIG_NAME SPI_CPU0_LVC3_SCM_CLK
J 0
(-3710 4285);
DISPLAY 0.489362 (-3710 4285);
WIRE 16 -1 (-8200 6000)(-8025 6000);
WIRE 16 -1 (-8200 6000)(-8200 5975);
WIRE 16 -1 (-8375 6000)(-8200 6000);
WIRE 16 -1 (-8025 6000)(-8025 6025);
WIRE 16 -1 (-8025 5975)(-8025 6000);
WIRE 16 -1 (-8375 5975)(-8375 6000);
WIRE 16 -1 (-8375 6000)(-8550 6000);
WIRE 16 -1 (-8550 6000)(-8550 5975);
WIRE 16 -1 (-8550 6000)(-8725 6000);
WIRE 16 -1 (-8725 6000)(-8725 5975);
WIRE 16 -1 (-8725 6000)(-8900 6000);
WIRE 16 -1 (-8900 6000)(-8900 5975);
WIRE 16 -1 (-8900 6000)(-9075 6000);
WIRE 16 -1 (-9075 6000)(-9075 5975);
WIRE 16 -1 (-9250 6000)(-9075 6000);
WIRE 16 -1 (-9250 6000)(-9250 5975);
WIRE 16 -1 (-5825 4025)(-6225 4025);
WIRE 16 -1 (-6225 4025)(-6225 3975);
WIRE 16 -1 (-6225 4050)(-6225 4025);
WIRE 16 -1 (-5825 3975)(-6225 3975);
WIRE 16 -1 (-6225 3975)(-6225 3925);
WIRE 16 -1 (-6225 3925)(-5825 3925);
WIRE 16 -1 (-6225 3925)(-6225 3875);
WIRE 16 -1 (-5825 3875)(-6225 3875);
WIRE 16 -1 (-4750 4850)(-4750 4900);
WIRE 16 -1 (-4750 4900)(-4875 4900);
WIRE 16 -1 (-4875 4525)(-4875 4900);
WIRE 16 -1 (-4875 4900)(-4875 4950);
WIRE 16 -1 (-5025 4525)(-4875 4525);
WIRE 16 -1 (-5975 4525)(-5975 4900);
WIRE 16 -1 (-5975 4525)(-5825 4525);
WIRE 16 -1 (-6100 4900)(-5975 4900);
WIRE 16 -1 (-5975 4900)(-5975 4925);
WIRE 16 -1 (-6100 4850)(-6100 4900);
WIRE 16 -1 (-5150 2475)(-4850 2475);
WIRE 16 -1 (-4850 2475)(-4850 2800);
WIRE 16 -1 (-4725 2800)(-4850 2800);
WIRE 16 -1 (-4850 2800)(-4850 2850);
WIRE 16 -1 (-4725 2750)(-4725 2800);
WIRE 16 -1 (-6075 2475)(-6075 2825);
WIRE 16 -1 (-6075 2475)(-5950 2475);
WIRE 16 -1 (-6200 2825)(-6075 2825);
WIRE 16 -1 (-6075 2825)(-6075 2850);
WIRE 16 -1 (-6200 2775)(-6200 2825);
WIRE 16 -1 (-2225 5725)(-2225 5775);
WIRE 16 -1 (-2225 5775)(-2050 5775);
WIRE 16 -1 (-2225 5875)(-2225 5775);
WIRE 16 -1 (-2050 5775)(-1875 5775);
WIRE 16 -1 (-2050 5725)(-2050 5775);
WIRE 16 -1 (-1875 5775)(-1700 5775);
WIRE 16 -1 (-1875 5725)(-1875 5775);
WIRE 16 -1 (-1700 5775)(-1525 5775);
WIRE 16 -1 (-1700 5725)(-1700 5775);
WIRE 16 -1 (-1525 5775)(-1350 5775);
WIRE 16 -1 (-1525 5725)(-1525 5775);
WIRE 16 -1 (-1350 5775)(-1175 5775);
WIRE 16 -1 (-1350 5725)(-1350 5775);
WIRE 16 -1 (-1175 5775)(-1025 5775);
WIRE 16 -1 (-1175 5775)(-1175 5725);
WIRE 16 -1 (-1025 5775)(-1025 5725);
WIRE 16 -1 (-7825 2275)(-6900 2275);
FORCEPROP 2 LAST SIG_NAME SPI_CPU0_D0
J 0
(-7635 2285);
DISPLAY 0.489362 (-7635 2285);
WIRE 16 -1 (-6900 2325)(-7825 2325);
FORCEPROP 2 LAST SIG_NAME SPI_CPU0_D2
J 0
(-7635 2335);
DISPLAY 0.489362 (-7635 2335);
WIRE 16 -1 (-6900 2375)(-7825 2375);
FORCEPROP 2 LAST SIG_NAME SPI_CPU0_D3
J 0
(-7635 2385);
DISPLAY 0.489362 (-7635 2385);
WIRE 16 -1 (-7825 2225)(-6900 2225);
FORCEPROP 2 LAST SIG_NAME SPI_CPU0_D1
J 0
(-7635 2235);
DISPLAY 0.489362 (-7635 2235);
WIRE 16 -1 (-6875 2125)(-5950 2125);
FORCEPROP 2 LAST SIG_NAME ROM_LS_EN
J 0
(-6685 2135);
DISPLAY 0.489362 (-6685 2135);
WIRE 16 -1 (-6700 2375)(-5950 2375);
FORCEPROP 2 LAST SIG_NAME SPI_CPU0_R1_D3
J 0
(-6510 2385);
DISPLAY 0.553191 (-6510 2385);
FORCEPROP 2 LASTPROP $XRERR UNIQUE?
J 0
(-6750 2385);
DISPLAY 0.638298 (-6750 2385);
PAINT MONO (-6750 2385);
DISPLAY INVISIBLE (-6750 2385);
WIRE 16 -1 (-6700 2225)(-5950 2225);
FORCEPROP 2 LAST SIG_NAME SPI_CPU0_R1_D1
J 0
(-6510 2235);
DISPLAY 0.553191 (-6510 2235);
FORCEPROP 2 LASTPROP $XRERR UNIQUE?
J 0
(-6750 2235);
DISPLAY 0.638298 (-6750 2235);
PAINT MONO (-6750 2235);
DISPLAY INVISIBLE (-6750 2235);
WIRE 16 -1 (-6700 2275)(-5950 2275);
FORCEPROP 2 LAST SIG_NAME SPI_CPU0_R1_D0
J 0
(-6510 2285);
DISPLAY 0.553191 (-6510 2285);
FORCEPROP 2 LASTPROP $XRERR UNIQUE?
J 0
(-6750 2285);
DISPLAY 0.638298 (-6750 2285);
PAINT MONO (-6750 2285);
DISPLAY INVISIBLE (-6750 2285);
WIRE 16 -1 (-6700 2325)(-5950 2325);
FORCEPROP 2 LAST SIG_NAME SPI_CPU0_R1_D2
J 0
(-6510 2335);
DISPLAY 0.553191 (-6510 2335);
FORCEPROP 2 LASTPROP $XRERR UNIQUE?
J 0
(-6750 2335);
DISPLAY 0.638298 (-6750 2335);
PAINT MONO (-6750 2335);
DISPLAY INVISIBLE (-6750 2335);
WIRE 16 -1 (-5825 3825)(-6750 3825);
FORCEPROP 2 LAST SIG_NAME ROM_SD_LS_OE
J 0
(-6560 3835);
DISPLAY 0.446809 (-6560 3835);
WIRE 16 -1 (-7150 5275)(-9075 5275);
FORCEPROP 2 LAST SIG_NAME SPI_CPU0_D3
J 0
(-7825 5285);
DISPLAY 0.489362 (-7825 5285);
WIRE 16 -1 (-9075 5275)(-9075 5775);
WIRE 16 -1 (-2225 5525)(-2225 5450);
WIRE 16 -1 (-2225 5450)(-3075 5450);
FORCEPROP 2 LAST SIG_NAME SPI_CPU0_LVC3_SCM_CLK
J 0
(-3000 5460);
DISPLAY 0.489362 (-3000 5460);
WIRE 16 -1 (-6750 4175)(-5825 4175);
FORCEPROP 2 LAST SIG_NAME SPI_CPU0_TPM_CS_N
J 0
(-6560 4185);
DISPLAY 0.489362 (-6560 4185);
WIRE 16 -1 (-6750 4325)(-5825 4325);
FORCEPROP 2 LAST SIG_NAME SPI_CPU0_CS0_N
J 0
(-6560 4335);
DISPLAY 0.489362 (-6560 4335);
WIRE 16 -1 (-6750 4275)(-5825 4275);
FORCEPROP 2 LAST SIG_NAME SPI_CPU0_CLK
J 0
(-6560 4285);
DISPLAY 0.489362 (-6560 4285);
WIRE 16 -1 (-3975 2225)(-3175 2225);
FORCEPROP 2 LAST SIG_NAME SPI_CPU0_LVC3_SCM_D1
J 0
(-3835 2235);
DISPLAY 0.489362 (-3835 2235);
WIRE 16 -1 (-3975 2275)(-3175 2275);
FORCEPROP 2 LAST SIG_NAME SPI_CPU0_LVC3_SCM_D0
J 0
(-3835 2285);
DISPLAY 0.489362 (-3835 2285);
WIRE 16 -1 (-5825 4225)(-6750 4225);
FORCEPROP 2 LAST SIG_NAME SPI_CPU0_CS1_N
J 0
(-6560 4235);
DISPLAY 0.489362 (-6560 4235);
WIRE 16 -1 (-3075 5150)(-1175 5150);
FORCEPROP 2 LAST SIG_NAME SPI_CPU0_LVC3_TPM_CS_N
J 0
(-3010 5160);
DISPLAY 0.446809 (-3010 5160);
WIRE 16 -1 (-1175 5525)(-1175 5150);
WIRE 16 -1 (-3175 2375)(-3975 2375);
FORCEPROP 2 LAST SIG_NAME SPI_CPU0_LVC3_SCM_D3
J 0
(-3825 2385);
DISPLAY 0.489362 (-3825 2385);
WIRE 16 -1 (-3175 2325)(-3975 2325);
FORCEPROP 2 LAST SIG_NAME SPI_CPU0_LVC3_SCM_D2
J 0
(-3825 2335);
DISPLAY 0.489362 (-3825 2335);
WIRE 16 -1 (-3075 5250)(-1525 5250);
FORCEPROP 2 LAST SIG_NAME SPI_CPU0_LVC3_SCM_D2
J 0
(-3000 5260);
DISPLAY 0.489362 (-3000 5260);
WIRE 16 -1 (-1525 5525)(-1525 5250);
WIRE 16 -1 (-3075 5200)(-1350 5200);
FORCEPROP 2 LAST SIG_NAME SPI_CPU0_LVC3_SCM_D3
J 0
(-3000 5210);
DISPLAY 0.489362 (-3000 5210);
WIRE 16 -1 (-1350 5525)(-1350 5200);
WIRE 16 -1 (-2050 5525)(-2050 5400);
WIRE 16 -1 (-2050 5400)(-3075 5400);
FORCEPROP 2 LAST SIG_NAME SPI_CPU0_LVC3_SCM_CS0_N
J 0
(-3000 5410);
DISPLAY 0.489362 (-3000 5410);
WIRE 16 -1 (-3075 5350)(-1875 5350);
FORCEPROP 2 LAST SIG_NAME SPI_CPU0_LVC3_SCM_D0
J 0
(-3000 5360);
DISPLAY 0.489362 (-3000 5360);
WIRE 16 -1 (-1875 5525)(-1875 5350);
WIRE 16 -1 (-3075 5300)(-1700 5300);
FORCEPROP 2 LAST SIG_NAME SPI_CPU0_LVC3_SCM_D1
J 0
(-3000 5310);
DISPLAY 0.489362 (-3000 5310);
WIRE 16 -1 (-1700 5525)(-1700 5300);
WIRE 16 -1 (-1025 5525)(-1025 5100);
WIRE 16 -1 (-1025 5100)(-3075 5100);
FORCEPROP 2 LAST SIG_NAME SPI_CPU0_LVC3_SCM_CS1_N
J 0
(-3010 5110);
DISPLAY 0.446809 (-3010 5110);
WIRE 16 -1 (-7150 5575)(-8025 5575);
FORCEPROP 2 LAST SIG_NAME SPI_CPU0_CS0_N
J 0
(-7825 5585);
DISPLAY 0.489362 (-7825 5585);
WIRE 16 -1 (-8025 5775)(-8025 5575);
WIRE 16 -1 (-8200 5775)(-8200 5525);
WIRE 16 -1 (-8200 5525)(-7150 5525);
FORCEPROP 2 LAST SIG_NAME SPI_CPU0_TPM_CS_N
J 0
(-7825 5535);
DISPLAY 0.489362 (-7825 5535);
WIRE 16 -1 (-7150 5475)(-8375 5475);
FORCEPROP 2 LAST SIG_NAME SPI_CPU0_CS1_N
J 0
(-7825 5485);
DISPLAY 0.489362 (-7825 5485);
WIRE 16 -1 (-8375 5775)(-8375 5475);
WIRE 16 -1 (-7150 5425)(-8550 5425);
FORCEPROP 2 LAST SIG_NAME SPI_CPU0_D0
J 0
(-7825 5435);
DISPLAY 0.489362 (-7825 5435);
WIRE 16 -1 (-8550 5775)(-8550 5425);
WIRE 16 -1 (-7150 5375)(-8725 5375);
FORCEPROP 2 LAST SIG_NAME SPI_CPU0_D1
J 0
(-7825 5385);
DISPLAY 0.489362 (-7825 5385);
WIRE 16 -1 (-8725 5375)(-8725 5775);
WIRE 16 -1 (-7150 5325)(-8900 5325);
FORCEPROP 2 LAST SIG_NAME SPI_CPU0_D2
J 0
(-7825 5335);
DISPLAY 0.489362 (-7825 5335);
WIRE 16 -1 (-8900 5325)(-8900 5775);
WIRE 16 -1 (-9250 5775)(-9250 5225);
WIRE 16 -1 (-9250 5225)(-7150 5225);
FORCEPROP 2 LAST SIG_NAME ROM_LS_EN
J 0
(-7810 5235);
DISPLAY 0.446809 (-7810 5235);
WIRE 16 -1 (-5150 2225)(-4175 2225);
FORCEPROP 2 LAST SIG_NAME SPI_CPU0_LVC3_D1
J 0
(-4910 2225);
DISPLAY 0.489362 (-4910 2225);
FORCEPROP 2 LASTPROP $XRERR UNIQUE?
J 0
(-5150 2225);
DISPLAY 0.638298 (-5150 2225);
PAINT MONO (-5150 2225);
DISPLAY INVISIBLE (-5150 2225);
WIRE 16 -1 (-5150 2275)(-4175 2275);
FORCEPROP 2 LAST SIG_NAME SPI_CPU0_LVC3_D0
J 0
(-4910 2275);
DISPLAY 0.489362 (-4910 2275);
FORCEPROP 2 LASTPROP $XRERR UNIQUE?
J 0
(-5150 2275);
DISPLAY 0.638298 (-5150 2275);
PAINT MONO (-5150 2275);
DISPLAY INVISIBLE (-5150 2275);
WIRE 16 -1 (-4175 2325)(-5150 2325);
FORCEPROP 2 LAST SIG_NAME SPI_CPU0_LVC3_D2
J 0
(-4910 2335);
DISPLAY 0.489362 (-4910 2335);
FORCEPROP 2 LASTPROP $XRERR UNIQUE?
J 0
(-5150 2335);
DISPLAY 0.638298 (-5150 2335);
PAINT MONO (-5150 2335);
DISPLAY INVISIBLE (-5150 2335);
WIRE 16 -1 (-4175 2375)(-5150 2375);
FORCEPROP 2 LAST SIG_NAME SPI_CPU0_LVC3_D3
J 0
(-4910 2385);
DISPLAY 0.489362 (-4910 2385);
FORCEPROP 2 LASTPROP $XRERR UNIQUE?
J 0
(-5150 2385);
DISPLAY 0.638298 (-5150 2385);
PAINT MONO (-5150 2385);
DISPLAY INVISIBLE (-5150 2385);
DOT 1 (-6225 3925);
DOT 1 (-5975 4900);
DOT 1 (-1175 5775);
DOT 1 (-6075 2825);
DOT 1 (-4875 4900);
DOT 1 (-4850 2800);
DOT 1 (-8900 6000);
DOT 1 (-8725 6000);
DOT 1 (-8025 6000);
DOT 1 (-1525 5775);
DOT 1 (-2225 5775);
DOT 1 (-1350 5775);
DOT 1 (-8375 6000);
DOT 1 (-9075 6000);
DOT 1 (-8200 6000);
DOT 1 (-8550 6000);
DOT 1 (-1700 5775);
DOT 1 (-1875 5775);
DOT 1 (-2050 5775);
DOT 1 (-6225 4025);
DOT 1 (-6225 3975);
FORCENOTE
CPU0 QSPI0 TO SCM QSPI0
(-6525 3225) 0;
DISPLAY LEFT (-6525 3225);
DISPLAY 2.000000 (-6525 3225);
PAINT WHITE (-6525 3225);
QUIT
